FILE_TYPE = MACRO_DRAWING;
SET COLOR_WIRE YELLOW;
SET COLOR_PROP ORANGE;
SET COLOR_DOT WHITE;
SET COLOR_ARC YELLOW;
SET COLOR_BODY GREEN;
SET COLOR_NOTE PURPLE;
SET PROP_DISPLAY VALUE;
SET PAGE_NUMBER P77;
FORCEADD Q_CAP..1
(-7250 2225);
FORCEPROP 1 LAST PART_NUMBER CH622KMEB01
J 0
(-7200 2075);
DISPLAY 0.638298 (-7200 2075);
DISPLAY INVISIBLE (-7200 2075);
FORCEPROP 1 LAST VOLTAGE 4V
J 0
(-7200 2225);
DISPLAY 0.638298 (-7200 2225);
FORCEPROP 1 LAST TOLERANCE 20%
J 0
(-7200 2175);
DISPLAY 0.638298 (-7200 2175);
FORCEPROP 1 LAST VALUE 22UF
J 0
(-7200 2275);
DISPLAY 0.638298 (-7200 2275);
FORCEPROP 1 LAST MATERIAL X6S
J 0
(-7200 2125);
DISPLAY 0.638298 (-7200 2125);
FORCEPROP 1 LAST PACK_TYPE C0402
J 0
(-7200 2025);
DISPLAY 0.638298 (-7200 2025);
FORCEPROP 1 LAST $LOCATION C424
J 0
(-7200 2325);
DISPLAY 0.978723 (-7200 2325);
FORCEPROP 1 LASTPIN (-7250 2325) $PN 1
J 0
(-7240 2305);
DISPLAY 0.787234 (-7240 2305);
FORCEPROP 1 LASTPIN (-7250 2125) $PN 2
J 0
(-7240 2105);
DISPLAY 0.787234 (-7240 2105);
FORCEPROP 2 LAST CDS_LIB pure_quanta
J 0
(-7250 2225);
PAINT MONO (-7250 2225);
DISPLAY INVISIBLE (-7250 2225);
FORCEPROP 2 LAST CDS_LOCATION C424
J 0
(-7200 2425);
DISPLAY 1.021277 (-7200 2425);
DISPLAY INVISIBLE (-7200 2425);
FORCEPROP 2 LAST $SEC 1
J 0
(-7200 2425);
DISPLAY 0.680851 (-7200 2425);
PAINT MONO (-7200 2425);
DISPLAY INVISIBLE (-7200 2425);
FORCEPROP 2 LAST CDS_SEC 1
J 0
(-7200 2425);
DISPLAY 1.021277 (-7200 2425);
DISPLAY INVISIBLE (-7200 2425);
FORCEPROP 1 LAST PATH I1
J 0
(-7200 2375);
DISPLAY 0.978723 (-7200 2375);
PAINT WHITE (-7200 2375);
DISPLAY INVISIBLE (-7200 2375);
FORCEADD Q_CAP..1
(-7250 3850);
FORCEPROP 1 LAST PART_NUMBER CH647KMEA04
J 0
(-7200 3700);
DISPLAY 0.638298 (-7200 3700);
DISPLAY INVISIBLE (-7200 3700);
FORCEPROP 1 LAST VOLTAGE 4V
J 0
(-7200 3850);
DISPLAY 0.638298 (-7200 3850);
FORCEPROP 1 LAST TOLERANCE 20%
J 0
(-7200 3800);
DISPLAY 0.638298 (-7200 3800);
FORCEPROP 1 LAST PACK_TYPE C0805
J 0
(-7200 3650);
DISPLAY 0.638298 (-7200 3650);
FORCEPROP 1 LAST VALUE 47UF
J 0
(-7200 3900);
DISPLAY 0.638298 (-7200 3900);
FORCEPROP 1 LAST MATERIAL X6S
J 0
(-7200 3750);
DISPLAY 0.638298 (-7200 3750);
FORCEPROP 1 LAST $LOCATION C225
J 0
(-7200 3950);
DISPLAY 0.638298 (-7200 3950);
FORCEPROP 1 LASTPIN (-7250 3950) $PN 1
J 0
(-7240 3930);
DISPLAY 0.787234 (-7240 3930);
FORCEPROP 1 LASTPIN (-7250 3750) $PN 2
J 0
(-7240 3730);
DISPLAY 0.787234 (-7240 3730);
FORCEPROP 2 LAST CDS_LIB pure_quanta
J 0
(-7250 3850);
PAINT MONO (-7250 3850);
DISPLAY INVISIBLE (-7250 3850);
FORCEPROP 1 LAST $LOCATION C225
J 0
(-7200 4050);
DISPLAY 1.021277 (-7200 4050);
DISPLAY INVISIBLE (-7200 4050);
FORCEPROP 2 LAST CDS_LOCATION C225
J 0
(-7200 4050);
DISPLAY 1.021277 (-7200 4050);
DISPLAY INVISIBLE (-7200 4050);
FORCEPROP 2 LAST $SEC 1
J 0
(-7200 4050);
DISPLAY 0.680851 (-7200 4050);
PAINT MONO (-7200 4050);
DISPLAY INVISIBLE (-7200 4050);
FORCEPROP 2 LAST CDS_SEC 1
J 0
(-7200 4050);
DISPLAY 1.021277 (-7200 4050);
DISPLAY INVISIBLE (-7200 4050);
FORCEPROP 1 LAST PATH I10
J 0
(-7200 4000);
DISPLAY 0.978723 (-7200 4000);
PAINT WHITE (-7200 4000);
DISPLAY INVISIBLE (-7200 4000);
FORCEADD Q_CAP..1
(-2750 6925);
FORCEPROP 1 LAST PART_NUMBER CH622KMEB01
J 0
(-2700 6775);
DISPLAY 0.638298 (-2700 6775);
DISPLAY INVISIBLE (-2700 6775);
FORCEPROP 1 LAST VOLTAGE 4V
J 0
(-2700 6925);
DISPLAY 0.638298 (-2700 6925);
FORCEPROP 1 LAST TOLERANCE 20%
J 0
(-2700 6875);
DISPLAY 0.638298 (-2700 6875);
FORCEPROP 1 LAST PACK_TYPE C0402
J 0
(-2700 6725);
DISPLAY 0.638298 (-2700 6725);
FORCEPROP 1 LAST MATERIAL X6S
J 0
(-2700 6825);
DISPLAY 0.638298 (-2700 6825);
FORCEPROP 1 LAST VALUE 22UF
J 0
(-2700 6975);
DISPLAY 0.638298 (-2700 6975);
FORCEPROP 1 LAST $LOCATION C271
J 0
(-2700 7025);
DISPLAY 0.638298 (-2700 7025);
FORCEPROP 1 LASTPIN (-2750 7025) $PN 1
J 0
(-2740 7005);
DISPLAY 0.787234 (-2740 7005);
FORCEPROP 1 LASTPIN (-2750 6825) $PN 2
J 0
(-2740 6805);
DISPLAY 0.787234 (-2740 6805);
FORCEPROP 2 LAST CDS_LIB pure_quanta
J 0
(-2750 6925);
PAINT MONO (-2750 6925);
DISPLAY INVISIBLE (-2750 6925);
FORCEPROP 1 LAST $LOCATION C271
J 0
(-2700 7125);
DISPLAY 1.021277 (-2700 7125);
DISPLAY INVISIBLE (-2700 7125);
FORCEPROP 2 LAST CDS_LOCATION C271
J 0
(-2700 7125);
DISPLAY 1.021277 (-2700 7125);
DISPLAY INVISIBLE (-2700 7125);
FORCEPROP 2 LAST $SEC 1
J 0
(-2700 7125);
DISPLAY 0.680851 (-2700 7125);
PAINT MONO (-2700 7125);
DISPLAY INVISIBLE (-2700 7125);
FORCEPROP 2 LAST CDS_SEC 1
J 0
(-2700 7125);
DISPLAY 1.021277 (-2700 7125);
DISPLAY INVISIBLE (-2700 7125);
FORCEPROP 1 LAST PATH I100
J 0
(-2700 7075);
DISPLAY 0.978723 (-2700 7075);
PAINT WHITE (-2700 7075);
DISPLAY INVISIBLE (-2700 7075);
FORCEADD Q_CAP..1
(-2275 5400);
FORCEPROP 1 LAST PART_NUMBER CH622KMEB01
J 0
(-2225 5250);
DISPLAY 0.638298 (-2225 5250);
DISPLAY INVISIBLE (-2225 5250);
FORCEPROP 1 LAST VOLTAGE 4V
J 0
(-2225 5400);
DISPLAY 0.638298 (-2225 5400);
FORCEPROP 1 LAST TOLERANCE 20%
J 0
(-2225 5350);
DISPLAY 0.638298 (-2225 5350);
FORCEPROP 1 LAST MATERIAL X6S
J 0
(-2225 5300);
DISPLAY 0.638298 (-2225 5300);
FORCEPROP 1 LAST PACK_TYPE C0402
J 0
(-2225 5200);
DISPLAY 0.638298 (-2225 5200);
FORCEPROP 1 LAST VALUE 22UF
J 0
(-2225 5450);
DISPLAY 0.638298 (-2225 5450);
FORCEPROP 1 LAST $LOCATION C277
J 0
(-2225 5500);
DISPLAY 0.638298 (-2225 5500);
FORCEPROP 1 LASTPIN (-2275 5500) $PN 1
J 0
(-2265 5480);
DISPLAY 0.787234 (-2265 5480);
FORCEPROP 1 LASTPIN (-2275 5300) $PN 2
J 0
(-2265 5280);
DISPLAY 0.787234 (-2265 5280);
FORCEPROP 2 LAST CDS_LIB pure_quanta
J 0
(-2275 5400);
PAINT MONO (-2275 5400);
DISPLAY INVISIBLE (-2275 5400);
FORCEPROP 1 LAST $LOCATION C277
J 0
(-2225 5600);
DISPLAY 1.021277 (-2225 5600);
DISPLAY INVISIBLE (-2225 5600);
FORCEPROP 2 LAST CDS_LOCATION C277
J 0
(-2225 5600);
DISPLAY 1.021277 (-2225 5600);
DISPLAY INVISIBLE (-2225 5600);
FORCEPROP 2 LAST $SEC 1
J 0
(-2225 5600);
DISPLAY 0.680851 (-2225 5600);
PAINT MONO (-2225 5600);
DISPLAY INVISIBLE (-2225 5600);
FORCEPROP 2 LAST CDS_SEC 1
J 0
(-2225 5600);
DISPLAY 1.021277 (-2225 5600);
DISPLAY INVISIBLE (-2225 5600);
FORCEPROP 1 LAST PATH I101
J 0
(-2225 5550);
DISPLAY 0.978723 (-2225 5550);
PAINT WHITE (-2225 5550);
DISPLAY INVISIBLE (-2225 5550);
FORCEADD Q_CAP..1
(-1825 5400);
FORCEPROP 1 LAST PART_NUMBER CH622KMEB01
J 0
(-1775 5250);
DISPLAY 0.638298 (-1775 5250);
DISPLAY INVISIBLE (-1775 5250);
FORCEPROP 1 LAST VOLTAGE 4V
J 0
(-1775 5400);
DISPLAY 0.638298 (-1775 5400);
FORCEPROP 1 LAST MATERIAL X6S
J 0
(-1775 5300);
DISPLAY 0.638298 (-1775 5300);
FORCEPROP 1 LAST TOLERANCE 20%
J 0
(-1775 5350);
DISPLAY 0.638298 (-1775 5350);
FORCEPROP 1 LAST VALUE 22UF
J 0
(-1775 5450);
DISPLAY 0.638298 (-1775 5450);
FORCEPROP 1 LAST PACK_TYPE C0402
J 0
(-1775 5200);
DISPLAY 0.638298 (-1775 5200);
FORCEPROP 1 LAST $LOCATION C281
J 0
(-1775 5500);
DISPLAY 0.638298 (-1775 5500);
FORCEPROP 1 LASTPIN (-1825 5500) $PN 1
J 0
(-1815 5480);
DISPLAY 0.787234 (-1815 5480);
FORCEPROP 1 LASTPIN (-1825 5300) $PN 2
J 0
(-1815 5280);
DISPLAY 0.787234 (-1815 5280);
FORCEPROP 2 LAST CDS_LIB pure_quanta
J 0
(-1825 5400);
PAINT MONO (-1825 5400);
DISPLAY INVISIBLE (-1825 5400);
FORCEPROP 1 LAST $LOCATION C281
J 0
(-1775 5600);
DISPLAY 1.021277 (-1775 5600);
DISPLAY INVISIBLE (-1775 5600);
FORCEPROP 2 LAST CDS_LOCATION C281
J 0
(-1775 5600);
DISPLAY 1.021277 (-1775 5600);
DISPLAY INVISIBLE (-1775 5600);
FORCEPROP 2 LAST $SEC 1
J 0
(-1775 5600);
DISPLAY 0.680851 (-1775 5600);
PAINT MONO (-1775 5600);
DISPLAY INVISIBLE (-1775 5600);
FORCEPROP 2 LAST CDS_SEC 1
J 0
(-1775 5600);
DISPLAY 1.021277 (-1775 5600);
DISPLAY INVISIBLE (-1775 5600);
FORCEPROP 1 LAST PATH I102
J 0
(-1775 5550);
DISPLAY 0.978723 (-1775 5550);
PAINT WHITE (-1775 5550);
DISPLAY INVISIBLE (-1775 5550);
FORCEADD Q_CAP..1
(-2300 6150);
FORCEPROP 1 LAST PART_NUMBER CH622KMEB01
J 0
(-2250 6000);
DISPLAY 0.638298 (-2250 6000);
DISPLAY INVISIBLE (-2250 6000);
FORCEPROP 1 LAST TOLERANCE 20%
J 0
(-2250 6100);
DISPLAY 0.638298 (-2250 6100);
FORCEPROP 1 LAST VOLTAGE 4V
J 0
(-2250 6150);
DISPLAY 0.638298 (-2250 6150);
FORCEPROP 1 LAST VALUE 22UF
J 0
(-2250 6200);
DISPLAY 0.638298 (-2250 6200);
FORCEPROP 1 LAST PACK_TYPE C0402
J 0
(-2250 5950);
DISPLAY 0.638298 (-2250 5950);
FORCEPROP 1 LAST MATERIAL X6S
J 0
(-2250 6050);
DISPLAY 0.638298 (-2250 6050);
FORCEPROP 1 LAST $LOCATION C276
J 0
(-2250 6250);
DISPLAY 0.638298 (-2250 6250);
FORCEPROP 1 LASTPIN (-2300 6250) $PN 1
J 0
(-2290 6230);
DISPLAY 0.787234 (-2290 6230);
FORCEPROP 1 LASTPIN (-2300 6050) $PN 2
J 0
(-2290 6030);
DISPLAY 0.787234 (-2290 6030);
FORCEPROP 2 LAST CDS_LIB pure_quanta
J 0
(-2300 6150);
PAINT MONO (-2300 6150);
DISPLAY INVISIBLE (-2300 6150);
FORCEPROP 1 LAST $LOCATION C276
J 0
(-2250 6350);
DISPLAY 1.021277 (-2250 6350);
DISPLAY INVISIBLE (-2250 6350);
FORCEPROP 2 LAST CDS_LOCATION C276
J 0
(-2250 6350);
DISPLAY 1.021277 (-2250 6350);
DISPLAY INVISIBLE (-2250 6350);
FORCEPROP 2 LAST $SEC 1
J 0
(-2250 6350);
DISPLAY 0.680851 (-2250 6350);
PAINT MONO (-2250 6350);
DISPLAY INVISIBLE (-2250 6350);
FORCEPROP 2 LAST CDS_SEC 1
J 0
(-2250 6350);
DISPLAY 1.021277 (-2250 6350);
DISPLAY INVISIBLE (-2250 6350);
FORCEPROP 1 LAST PATH I103
J 0
(-2250 6300);
DISPLAY 0.978723 (-2250 6300);
PAINT WHITE (-2250 6300);
DISPLAY INVISIBLE (-2250 6300);
FORCEADD Q_CAP..1
(-2300 6925);
FORCEPROP 1 LAST PART_NUMBER CH622KMEB01
J 0
(-2250 6775);
DISPLAY 0.638298 (-2250 6775);
DISPLAY INVISIBLE (-2250 6775);
FORCEPROP 1 LAST VOLTAGE 4V
J 0
(-2250 6925);
DISPLAY 0.638298 (-2250 6925);
FORCEPROP 1 LAST TOLERANCE 20%
J 0
(-2250 6875);
DISPLAY 0.638298 (-2250 6875);
FORCEPROP 1 LAST PACK_TYPE C0402
J 0
(-2250 6725);
DISPLAY 0.638298 (-2250 6725);
FORCEPROP 1 LAST MATERIAL X6S
J 0
(-2250 6825);
DISPLAY 0.638298 (-2250 6825);
FORCEPROP 1 LAST VALUE 22UF
J 0
(-2250 6975);
DISPLAY 0.638298 (-2250 6975);
FORCEPROP 1 LAST $LOCATION C275
J 0
(-2250 7025);
DISPLAY 0.638298 (-2250 7025);
FORCEPROP 1 LASTPIN (-2300 7025) $PN 1
J 0
(-2290 7005);
DISPLAY 0.787234 (-2290 7005);
FORCEPROP 1 LASTPIN (-2300 6825) $PN 2
J 0
(-2290 6805);
DISPLAY 0.787234 (-2290 6805);
FORCEPROP 2 LAST CDS_LIB pure_quanta
J 0
(-2300 6925);
PAINT MONO (-2300 6925);
DISPLAY INVISIBLE (-2300 6925);
FORCEPROP 1 LAST $LOCATION C275
J 0
(-2250 7125);
DISPLAY 1.021277 (-2250 7125);
DISPLAY INVISIBLE (-2250 7125);
FORCEPROP 2 LAST CDS_LOCATION C275
J 0
(-2250 7125);
DISPLAY 1.021277 (-2250 7125);
DISPLAY INVISIBLE (-2250 7125);
FORCEPROP 2 LAST $SEC 1
J 0
(-2250 7125);
DISPLAY 0.680851 (-2250 7125);
PAINT MONO (-2250 7125);
DISPLAY INVISIBLE (-2250 7125);
FORCEPROP 2 LAST CDS_SEC 1
J 0
(-2250 7125);
DISPLAY 1.021277 (-2250 7125);
DISPLAY INVISIBLE (-2250 7125);
FORCEPROP 1 LAST PATH I104
J 0
(-2250 7075);
DISPLAY 0.978723 (-2250 7075);
PAINT WHITE (-2250 7075);
DISPLAY INVISIBLE (-2250 7075);
FORCEADD Q_CAP..1
(-1850 6150);
FORCEPROP 1 LAST PART_NUMBER CH622KMEB01
J 0
(-1800 6000);
DISPLAY 0.638298 (-1800 6000);
DISPLAY INVISIBLE (-1800 6000);
FORCEPROP 1 LAST VOLTAGE 4V
J 0
(-1800 6150);
DISPLAY 0.638298 (-1800 6150);
FORCEPROP 1 LAST VALUE 22UF
J 0
(-1800 6200);
DISPLAY 0.638298 (-1800 6200);
FORCEPROP 1 LAST TOLERANCE 20%
J 0
(-1800 6100);
DISPLAY 0.638298 (-1800 6100);
FORCEPROP 1 LAST MATERIAL X6S
J 0
(-1800 6050);
DISPLAY 0.638298 (-1800 6050);
FORCEPROP 1 LAST PACK_TYPE C0402
J 0
(-1800 5950);
DISPLAY 0.638298 (-1800 5950);
FORCEPROP 1 LAST $LOCATION C280
J 0
(-1800 6250);
DISPLAY 0.638298 (-1800 6250);
FORCEPROP 1 LASTPIN (-1850 6250) $PN 1
J 0
(-1840 6230);
DISPLAY 0.787234 (-1840 6230);
FORCEPROP 1 LASTPIN (-1850 6050) $PN 2
J 0
(-1840 6030);
DISPLAY 0.787234 (-1840 6030);
FORCEPROP 2 LAST CDS_LIB pure_quanta
J 0
(-1850 6150);
PAINT MONO (-1850 6150);
DISPLAY INVISIBLE (-1850 6150);
FORCEPROP 1 LAST $LOCATION C280
J 0
(-1800 6350);
DISPLAY 1.021277 (-1800 6350);
DISPLAY INVISIBLE (-1800 6350);
FORCEPROP 2 LAST CDS_LOCATION C280
J 0
(-1800 6350);
DISPLAY 1.021277 (-1800 6350);
DISPLAY INVISIBLE (-1800 6350);
FORCEPROP 2 LAST $SEC 1
J 0
(-1800 6350);
DISPLAY 0.680851 (-1800 6350);
PAINT MONO (-1800 6350);
DISPLAY INVISIBLE (-1800 6350);
FORCEPROP 2 LAST CDS_SEC 1
J 0
(-1800 6350);
DISPLAY 1.021277 (-1800 6350);
DISPLAY INVISIBLE (-1800 6350);
FORCEPROP 1 LAST PATH I105
J 0
(-1800 6300);
DISPLAY 0.978723 (-1800 6300);
PAINT WHITE (-1800 6300);
DISPLAY INVISIBLE (-1800 6300);
FORCEADD Q_CAP..1
(-1850 6925);
FORCEPROP 1 LAST PART_NUMBER CH622KMEB01
J 0
(-1800 6775);
DISPLAY 0.638298 (-1800 6775);
DISPLAY INVISIBLE (-1800 6775);
FORCEPROP 1 LAST VOLTAGE 4V
J 0
(-1800 6925);
DISPLAY 0.638298 (-1800 6925);
FORCEPROP 1 LAST TOLERANCE 20%
J 0
(-1800 6875);
DISPLAY 0.638298 (-1800 6875);
FORCEPROP 1 LAST MATERIAL X6S
J 0
(-1800 6825);
DISPLAY 0.638298 (-1800 6825);
FORCEPROP 1 LAST VALUE 22UF
J 0
(-1800 6975);
DISPLAY 0.638298 (-1800 6975);
FORCEPROP 1 LAST PACK_TYPE C0402
J 0
(-1800 6725);
DISPLAY 0.638298 (-1800 6725);
FORCEPROP 1 LAST $LOCATION C279
J 0
(-1800 7025);
DISPLAY 0.638298 (-1800 7025);
FORCEPROP 1 LASTPIN (-1850 7025) $PN 1
J 0
(-1840 7005);
DISPLAY 0.787234 (-1840 7005);
FORCEPROP 1 LASTPIN (-1850 6825) $PN 2
J 0
(-1840 6805);
DISPLAY 0.787234 (-1840 6805);
FORCEPROP 2 LAST CDS_LIB pure_quanta
J 0
(-1850 6925);
PAINT MONO (-1850 6925);
DISPLAY INVISIBLE (-1850 6925);
FORCEPROP 1 LAST $LOCATION C279
J 0
(-1800 7125);
DISPLAY 1.021277 (-1800 7125);
DISPLAY INVISIBLE (-1800 7125);
FORCEPROP 2 LAST CDS_LOCATION C279
J 0
(-1800 7125);
DISPLAY 1.021277 (-1800 7125);
DISPLAY INVISIBLE (-1800 7125);
FORCEPROP 2 LAST $SEC 1
J 0
(-1800 7125);
DISPLAY 0.680851 (-1800 7125);
PAINT MONO (-1800 7125);
DISPLAY INVISIBLE (-1800 7125);
FORCEPROP 2 LAST CDS_SEC 1
J 0
(-1800 7125);
DISPLAY 1.021277 (-1800 7125);
DISPLAY INVISIBLE (-1800 7125);
FORCEPROP 1 LAST PATH I106
J 0
(-1800 7075);
DISPLAY 0.978723 (-1800 7075);
PAINT WHITE (-1800 7075);
DISPLAY INVISIBLE (-1800 7075);
FORCEADD UNIVERSAL_POWER..1
(-2750 7200);
FORCEPROP 3 LASTPIN (-2750 7150) SIG_NAME PVCCIN_CPU1\g
J 0
(-2740 7160);
DISPLAY 0.659574 (-2740 7160);
PAINT MONO (-2740 7160);
DISPLAY INVISIBLE (-2740 7160);
FORCEPROP 1 LAST HDL_POWER PVCCIN_CPU1
J 1
(-2550 7250);
DISPLAY 0.872340 (-2550 7250);
PAINT GREEN (-2550 7250);
FORCEPROP 2 LAST CDS_LIB logical_power
J 0
(-2750 7200);
DISPLAY INVISIBLE (-2750 7200);
FORCEPROP 1 LAST PATH I107
J 0
(-2700 7225);
DISPLAY 0.872340 (-2700 7225);
PAINT AQUA (-2700 7225);
DISPLAY INVISIBLE (-2700 7225);
FORCEADD UNIVERSAL_GND..1
(-625 2725);
FORCEPROP 3 LASTPIN (-625 2775) SIG_NAME GND\g
J 0
(-615 2785);
DISPLAY 0.659574 (-615 2785);
PAINT MONO (-615 2785);
DISPLAY INVISIBLE (-615 2785);
FORCEPROP 2 LAST CDS_LIB logical_power
J 0
(-625 2725);
PAINT MONO (-625 2725);
DISPLAY INVISIBLE (-625 2725);
FORCEPROP 1 LAST HDL_POWER GND
J 1
(-600 2650);
DISPLAY 0.872340 (-600 2650);
PAINT GREEN (-600 2650);
DISPLAY INVISIBLE (-600 2650);
FORCEPROP 1 LAST PATH I108
J 0
(-550 2725);
DISPLAY 0.872340 (-550 2725);
PAINT AQUA (-550 2725);
DISPLAY INVISIBLE (-550 2725);
FORCEADD Q_CAP..1
(-1525 3050);
FORCEPROP 1 LAST PART_NUMBER CH622KMEB01
J 0
(-1475 2900);
DISPLAY 0.638298 (-1475 2900);
DISPLAY INVISIBLE (-1475 2900);
FORCEPROP 1 LAST VALUE 22UF
J 0
(-1475 3100);
DISPLAY 0.638298 (-1475 3100);
FORCEPROP 1 LAST VOLTAGE 4V
J 0
(-1475 3050);
DISPLAY 0.638298 (-1475 3050);
FORCEPROP 1 LAST TOLERANCE 20%
J 0
(-1475 3000);
DISPLAY 0.638298 (-1475 3000);
FORCEPROP 1 LAST PACK_TYPE C0402
J 0
(-1475 2850);
DISPLAY 0.638298 (-1475 2850);
FORCEPROP 1 LAST MATERIAL X6S
J 0
(-1475 2950);
DISPLAY 0.638298 (-1475 2950);
FORCEPROP 1 LAST $LOCATION C444
J 0
(-1475 3150);
DISPLAY 0.978723 (-1475 3150);
FORCEPROP 1 LASTPIN (-1525 3150) $PN 1
J 0
(-1515 3130);
DISPLAY 0.787234 (-1515 3130);
FORCEPROP 1 LASTPIN (-1525 2950) $PN 2
J 0
(-1515 2930);
DISPLAY 0.787234 (-1515 2930);
FORCEPROP 2 LAST CDS_LIB pure_quanta
J 0
(-1525 3050);
PAINT MONO (-1525 3050);
DISPLAY INVISIBLE (-1525 3050);
FORCEPROP 2 LAST CDS_LOCATION C444
J 0
(-1475 3250);
DISPLAY 1.021277 (-1475 3250);
DISPLAY INVISIBLE (-1475 3250);
FORCEPROP 2 LAST $SEC 1
J 0
(-1475 3250);
DISPLAY 0.680851 (-1475 3250);
PAINT MONO (-1475 3250);
DISPLAY INVISIBLE (-1475 3250);
FORCEPROP 2 LAST CDS_SEC 1
J 0
(-1475 3250);
DISPLAY 1.021277 (-1475 3250);
DISPLAY INVISIBLE (-1475 3250);
FORCEPROP 1 LAST PATH I109
J 0
(-1475 3200);
DISPLAY 0.978723 (-1475 3200);
PAINT WHITE (-1475 3200);
DISPLAY INVISIBLE (-1475 3200);
FORCEADD Q_CAP..1
(-6800 3850);
FORCEPROP 1 LAST PART_NUMBER CH647KMEA04
J 0
(-6750 3700);
DISPLAY 0.638298 (-6750 3700);
DISPLAY INVISIBLE (-6750 3700);
FORCEPROP 1 LAST TOLERANCE 20%
J 0
(-6750 3800);
DISPLAY 0.638298 (-6750 3800);
FORCEPROP 1 LAST VOLTAGE 4V
J 0
(-6750 3850);
DISPLAY 0.638298 (-6750 3850);
FORCEPROP 1 LAST PACK_TYPE C0805
J 0
(-6750 3650);
DISPLAY 0.638298 (-6750 3650);
FORCEPROP 1 LAST VALUE 47UF
J 0
(-6750 3900);
DISPLAY 0.638298 (-6750 3900);
FORCEPROP 1 LAST MATERIAL X6S
J 0
(-6750 3750);
DISPLAY 0.638298 (-6750 3750);
FORCEPROP 1 LAST $LOCATION C230
J 0
(-6750 3950);
DISPLAY 0.638298 (-6750 3950);
FORCEPROP 1 LASTPIN (-6800 3950) $PN 1
J 0
(-6790 3930);
DISPLAY 0.787234 (-6790 3930);
FORCEPROP 1 LASTPIN (-6800 3750) $PN 2
J 0
(-6790 3730);
DISPLAY 0.787234 (-6790 3730);
FORCEPROP 2 LAST CDS_LIB pure_quanta
J 0
(-6800 3850);
PAINT MONO (-6800 3850);
DISPLAY INVISIBLE (-6800 3850);
FORCEPROP 1 LAST $LOCATION C230
J 0
(-6750 4050);
DISPLAY 1.021277 (-6750 4050);
DISPLAY INVISIBLE (-6750 4050);
FORCEPROP 2 LAST CDS_LOCATION C230
J 0
(-6750 4050);
DISPLAY 1.021277 (-6750 4050);
DISPLAY INVISIBLE (-6750 4050);
FORCEPROP 2 LAST $SEC 1
J 0
(-6750 4050);
DISPLAY 0.680851 (-6750 4050);
PAINT MONO (-6750 4050);
DISPLAY INVISIBLE (-6750 4050);
FORCEPROP 2 LAST CDS_SEC 1
J 0
(-6750 4050);
DISPLAY 1.021277 (-6750 4050);
DISPLAY INVISIBLE (-6750 4050);
FORCEPROP 1 LAST PATH I11
J 0
(-6750 4000);
DISPLAY 0.978723 (-6750 4000);
PAINT WHITE (-6750 4000);
DISPLAY INVISIBLE (-6750 4000);
FORCEADD Q_CAP..1
(-1075 3050);
FORCEPROP 1 LAST PART_NUMBER CH622KMEB01
J 0
(-1025 2900);
DISPLAY 0.638298 (-1025 2900);
DISPLAY INVISIBLE (-1025 2900);
FORCEPROP 1 LAST TOLERANCE 20%
J 0
(-1025 3000);
DISPLAY 0.638298 (-1025 3000);
FORCEPROP 1 LAST VALUE 22UF
J 0
(-1025 3100);
DISPLAY 0.638298 (-1025 3100);
FORCEPROP 1 LAST VOLTAGE 4V
J 0
(-1025 3050);
DISPLAY 0.638298 (-1025 3050);
FORCEPROP 1 LAST MATERIAL X6S
J 0
(-1025 2950);
DISPLAY 0.638298 (-1025 2950);
FORCEPROP 1 LAST PACK_TYPE C0402
J 0
(-1025 2850);
DISPLAY 0.638298 (-1025 2850);
FORCEPROP 1 LAST $LOCATION C445
J 0
(-1025 3150);
DISPLAY 0.978723 (-1025 3150);
FORCEPROP 1 LASTPIN (-1075 3150) $PN 1
J 0
(-1065 3130);
DISPLAY 0.787234 (-1065 3130);
FORCEPROP 1 LASTPIN (-1075 2950) $PN 2
J 0
(-1065 2930);
DISPLAY 0.787234 (-1065 2930);
FORCEPROP 2 LAST CDS_LIB pure_quanta
J 0
(-1075 3050);
PAINT MONO (-1075 3050);
DISPLAY INVISIBLE (-1075 3050);
FORCEPROP 2 LAST CDS_LOCATION C445
J 0
(-1025 3250);
DISPLAY 1.021277 (-1025 3250);
DISPLAY INVISIBLE (-1025 3250);
FORCEPROP 2 LAST $SEC 1
J 0
(-1025 3250);
DISPLAY 0.680851 (-1025 3250);
PAINT MONO (-1025 3250);
DISPLAY INVISIBLE (-1025 3250);
FORCEPROP 2 LAST CDS_SEC 1
J 0
(-1025 3250);
DISPLAY 1.021277 (-1025 3250);
DISPLAY INVISIBLE (-1025 3250);
FORCEPROP 1 LAST PATH I110
J 0
(-1025 3200);
DISPLAY 0.978723 (-1025 3200);
PAINT WHITE (-1025 3200);
DISPLAY INVISIBLE (-1025 3200);
FORCEADD Q_CAP..1
(-1375 4625);
FORCEPROP 1 LAST PART_NUMBER CH622KMEB01
J 0
(-1325 4475);
DISPLAY 0.638298 (-1325 4475);
DISPLAY INVISIBLE (-1325 4475);
FORCEPROP 1 LAST VOLTAGE 4V
J 0
(-1325 4625);
DISPLAY 0.638298 (-1325 4625);
FORCEPROP 1 LAST TOLERANCE 20%
J 0
(-1325 4575);
DISPLAY 0.638298 (-1325 4575);
FORCEPROP 1 LAST PACK_TYPE C0402
J 0
(-1325 4425);
DISPLAY 0.638298 (-1325 4425);
FORCEPROP 1 LAST MATERIAL X6S
J 0
(-1325 4525);
DISPLAY 0.638298 (-1325 4525);
FORCEPROP 1 LAST VALUE 22UF
J 0
(-1325 4675);
DISPLAY 0.638298 (-1325 4675);
FORCEPROP 1 LAST $LOCATION C286
J 0
(-1325 4725);
DISPLAY 0.638298 (-1325 4725);
FORCEPROP 1 LASTPIN (-1375 4725) $PN 1
J 0
(-1365 4705);
DISPLAY 0.787234 (-1365 4705);
FORCEPROP 1 LASTPIN (-1375 4525) $PN 2
J 0
(-1365 4505);
DISPLAY 0.787234 (-1365 4505);
FORCEPROP 2 LAST CDS_LIB pure_quanta
J 0
(-1375 4625);
PAINT MONO (-1375 4625);
DISPLAY INVISIBLE (-1375 4625);
FORCEPROP 1 LAST $LOCATION C286
J 0
(-1325 4825);
DISPLAY 1.021277 (-1325 4825);
DISPLAY INVISIBLE (-1325 4825);
FORCEPROP 2 LAST CDS_LOCATION C286
J 0
(-1325 4825);
DISPLAY 1.021277 (-1325 4825);
DISPLAY INVISIBLE (-1325 4825);
FORCEPROP 2 LAST $SEC 1
J 0
(-1325 4825);
DISPLAY 0.680851 (-1325 4825);
PAINT MONO (-1325 4825);
DISPLAY INVISIBLE (-1325 4825);
FORCEPROP 2 LAST CDS_SEC 1
J 0
(-1325 4825);
DISPLAY 1.021277 (-1325 4825);
DISPLAY INVISIBLE (-1325 4825);
FORCEPROP 1 LAST PATH I111
J 0
(-1325 4775);
DISPLAY 0.978723 (-1325 4775);
PAINT WHITE (-1325 4775);
DISPLAY INVISIBLE (-1325 4775);
FORCEADD Q_CAP..1
(-925 4625);
FORCEPROP 1 LAST PART_NUMBER CH622KMEB01
J 0
(-875 4475);
DISPLAY 0.638298 (-875 4475);
DISPLAY INVISIBLE (-875 4475);
FORCEPROP 1 LAST TOLERANCE 20%
J 0
(-875 4575);
DISPLAY 0.638298 (-875 4575);
FORCEPROP 1 LAST VOLTAGE 4V
J 0
(-875 4625);
DISPLAY 0.638298 (-875 4625);
FORCEPROP 1 LAST MATERIAL X6S
J 0
(-875 4525);
DISPLAY 0.638298 (-875 4525);
FORCEPROP 1 LAST VALUE 22UF
J 0
(-875 4675);
DISPLAY 0.638298 (-875 4675);
FORCEPROP 1 LAST PACK_TYPE C0402
J 0
(-875 4425);
DISPLAY 0.638298 (-875 4425);
FORCEPROP 1 LAST $LOCATION C290
J 0
(-875 4725);
DISPLAY 0.638298 (-875 4725);
FORCEPROP 1 LASTPIN (-925 4725) $PN 1
J 0
(-915 4705);
DISPLAY 0.787234 (-915 4705);
FORCEPROP 1 LASTPIN (-925 4525) $PN 2
J 0
(-915 4505);
DISPLAY 0.787234 (-915 4505);
FORCEPROP 2 LAST CDS_LIB pure_quanta
J 0
(-925 4625);
PAINT MONO (-925 4625);
DISPLAY INVISIBLE (-925 4625);
FORCEPROP 1 LAST $LOCATION C290
J 0
(-875 4825);
DISPLAY 1.021277 (-875 4825);
DISPLAY INVISIBLE (-875 4825);
FORCEPROP 2 LAST CDS_LOCATION C290
J 0
(-875 4825);
DISPLAY 1.021277 (-875 4825);
DISPLAY INVISIBLE (-875 4825);
FORCEPROP 2 LAST $SEC 1
J 0
(-875 4825);
DISPLAY 0.680851 (-875 4825);
PAINT MONO (-875 4825);
DISPLAY INVISIBLE (-875 4825);
FORCEPROP 2 LAST CDS_SEC 1
J 0
(-875 4825);
DISPLAY 1.021277 (-875 4825);
DISPLAY INVISIBLE (-875 4825);
FORCEPROP 1 LAST PATH I112
J 0
(-875 4775);
DISPLAY 0.978723 (-875 4775);
PAINT WHITE (-875 4775);
DISPLAY INVISIBLE (-875 4775);
FORCEADD Q_CAP..1
(-625 3050);
FORCEPROP 1 LAST PART_NUMBER CH622KMEB01
J 0
(-575 2900);
DISPLAY 0.638298 (-575 2900);
DISPLAY INVISIBLE (-575 2900);
FORCEPROP 1 LAST VALUE 22UF
J 0
(-575 3100);
DISPLAY 0.638298 (-575 3100);
FORCEPROP 1 LAST VOLTAGE 4V
J 0
(-575 3050);
DISPLAY 0.638298 (-575 3050);
FORCEPROP 1 LAST TOLERANCE 20%
J 0
(-575 3000);
DISPLAY 0.638298 (-575 3000);
FORCEPROP 1 LAST MATERIAL X6S
J 0
(-575 2950);
DISPLAY 0.638298 (-575 2950);
FORCEPROP 1 LAST PACK_TYPE C0402
J 0
(-575 2850);
DISPLAY 0.638298 (-575 2850);
FORCEPROP 1 LAST $LOCATION C446
J 0
(-575 3150);
DISPLAY 0.978723 (-575 3150);
FORCEPROP 1 LASTPIN (-625 3150) $PN 1
J 0
(-615 3130);
DISPLAY 0.787234 (-615 3130);
FORCEPROP 1 LASTPIN (-625 2950) $PN 2
J 0
(-615 2930);
DISPLAY 0.787234 (-615 2930);
FORCEPROP 2 LAST CDS_LIB pure_quanta
J 0
(-625 3050);
PAINT MONO (-625 3050);
DISPLAY INVISIBLE (-625 3050);
FORCEPROP 2 LAST CDS_LOCATION C446
J 0
(-575 3250);
DISPLAY 1.021277 (-575 3250);
DISPLAY INVISIBLE (-575 3250);
FORCEPROP 2 LAST $SEC 1
J 0
(-575 3250);
DISPLAY 0.680851 (-575 3250);
PAINT MONO (-575 3250);
DISPLAY INVISIBLE (-575 3250);
FORCEPROP 2 LAST CDS_SEC 1
J 0
(-575 3250);
DISPLAY 1.021277 (-575 3250);
DISPLAY INVISIBLE (-575 3250);
FORCEPROP 1 LAST PATH I113
J 0
(-575 3200);
DISPLAY 0.978723 (-575 3200);
PAINT WHITE (-575 3200);
DISPLAY INVISIBLE (-575 3200);
FORCEADD Q_CAP..1
(-475 4625);
FORCEPROP 1 LAST PART_NUMBER CH622KMEB01
J 0
(-425 4475);
DISPLAY 0.638298 (-425 4475);
DISPLAY INVISIBLE (-425 4475);
FORCEPROP 1 LAST VOLTAGE 4V
J 0
(-425 4625);
DISPLAY 0.638298 (-425 4625);
FORCEPROP 1 LAST TOLERANCE 20%
J 0
(-425 4575);
DISPLAY 0.638298 (-425 4575);
FORCEPROP 1 LAST VALUE 22UF
J 0
(-425 4675);
DISPLAY 0.638298 (-425 4675);
FORCEPROP 1 LAST PACK_TYPE C0402
J 0
(-425 4425);
DISPLAY 0.638298 (-425 4425);
FORCEPROP 1 LAST MATERIAL X6S
J 0
(-425 4525);
DISPLAY 0.638298 (-425 4525);
FORCEPROP 1 LAST $LOCATION C294
J 0
(-425 4725);
DISPLAY 0.638298 (-425 4725);
FORCEPROP 1 LASTPIN (-475 4725) $PN 1
J 0
(-465 4705);
DISPLAY 0.787234 (-465 4705);
FORCEPROP 1 LASTPIN (-475 4525) $PN 2
J 0
(-465 4505);
DISPLAY 0.787234 (-465 4505);
FORCEPROP 2 LAST CDS_LIB pure_quanta
J 0
(-475 4625);
PAINT MONO (-475 4625);
DISPLAY INVISIBLE (-475 4625);
FORCEPROP 1 LAST $LOCATION C294
J 0
(-425 4825);
DISPLAY 1.021277 (-425 4825);
DISPLAY INVISIBLE (-425 4825);
FORCEPROP 2 LAST CDS_LOCATION C294
J 0
(-425 4825);
DISPLAY 1.021277 (-425 4825);
DISPLAY INVISIBLE (-425 4825);
FORCEPROP 2 LAST $SEC 1
J 0
(-425 4825);
DISPLAY 0.680851 (-425 4825);
PAINT MONO (-425 4825);
DISPLAY INVISIBLE (-425 4825);
FORCEPROP 2 LAST CDS_SEC 1
J 0
(-425 4825);
DISPLAY 1.021277 (-425 4825);
DISPLAY INVISIBLE (-425 4825);
FORCEPROP 1 LAST PATH I114
J 0
(-425 4775);
DISPLAY 0.978723 (-425 4775);
PAINT WHITE (-425 4775);
DISPLAY INVISIBLE (-425 4775);
FORCEADD Q_CAP..1
(-25 4625);
FORCEPROP 1 LAST PART_NUMBER CH622KMEB01
J 0
(25 4475);
DISPLAY 0.638298 (25 4475);
DISPLAY INVISIBLE (25 4475);
FORCEPROP 1 LAST TOLERANCE 20%
J 0
(25 4575);
DISPLAY 0.638298 (25 4575);
FORCEPROP 1 LAST VOLTAGE 4V
J 0
(25 4625);
DISPLAY 0.638298 (25 4625);
FORCEPROP 1 LAST MATERIAL X6S
J 0
(25 4525);
DISPLAY 0.638298 (25 4525);
FORCEPROP 1 LAST VALUE 22UF
J 0
(25 4675);
DISPLAY 0.638298 (25 4675);
FORCEPROP 1 LAST PACK_TYPE C0402
J 0
(25 4425);
DISPLAY 0.638298 (25 4425);
FORCEPROP 1 LAST $LOCATION C298
J 0
(25 4725);
DISPLAY 0.638298 (25 4725);
FORCEPROP 1 LASTPIN (-25 4725) $PN 1
J 0
(-15 4705);
DISPLAY 0.787234 (-15 4705);
FORCEPROP 1 LASTPIN (-25 4525) $PN 2
J 0
(-15 4505);
DISPLAY 0.787234 (-15 4505);
FORCEPROP 2 LAST CDS_LIB pure_quanta
J 0
(-25 4625);
PAINT MONO (-25 4625);
DISPLAY INVISIBLE (-25 4625);
FORCEPROP 1 LAST $LOCATION C298
J 0
(25 4825);
DISPLAY 1.021277 (25 4825);
DISPLAY INVISIBLE (25 4825);
FORCEPROP 2 LAST CDS_LOCATION C298
J 0
(25 4825);
DISPLAY 1.021277 (25 4825);
DISPLAY INVISIBLE (25 4825);
FORCEPROP 2 LAST $SEC 1
J 0
(25 4825);
DISPLAY 0.680851 (25 4825);
PAINT MONO (25 4825);
DISPLAY INVISIBLE (25 4825);
FORCEPROP 2 LAST CDS_SEC 1
J 0
(25 4825);
DISPLAY 1.021277 (25 4825);
DISPLAY INVISIBLE (25 4825);
FORCEPROP 1 LAST PATH I115
J 0
(25 4775);
DISPLAY 0.978723 (25 4775);
PAINT WHITE (25 4775);
DISPLAY INVISIBLE (25 4775);
FORCEADD UNIVERSAL_GND..1
(875 4275);
FORCEPROP 3 LASTPIN (875 4325) SIG_NAME GND\g
J 0
(885 4335);
DISPLAY 0.659574 (885 4335);
PAINT MONO (885 4335);
DISPLAY INVISIBLE (885 4335);
FORCEPROP 2 LAST CDS_LIB logical_power
J 0
(875 4275);
DISPLAY INVISIBLE (875 4275);
FORCEPROP 1 LAST HDL_POWER GND
J 1
(900 4200);
DISPLAY 0.872340 (900 4200);
PAINT GREEN (900 4200);
DISPLAY INVISIBLE (900 4200);
FORCEPROP 1 LAST PATH I116
J 0
(950 4275);
DISPLAY 0.872340 (950 4275);
PAINT AQUA (950 4275);
DISPLAY INVISIBLE (950 4275);
FORCEADD Q_CAP..1
(425 4625);
FORCEPROP 1 LAST PART_NUMBER CH622KMEB01
J 0
(475 4475);
DISPLAY 0.638298 (475 4475);
DISPLAY INVISIBLE (475 4475);
FORCEPROP 1 LAST TOLERANCE 20%
J 0
(475 4575);
DISPLAY 0.638298 (475 4575);
FORCEPROP 1 LAST VOLTAGE 4V
J 0
(475 4625);
DISPLAY 0.638298 (475 4625);
FORCEPROP 1 LAST MATERIAL X6S
J 0
(475 4525);
DISPLAY 0.638298 (475 4525);
FORCEPROP 1 LAST VALUE 22UF
J 0
(475 4675);
DISPLAY 0.638298 (475 4675);
FORCEPROP 1 LAST PACK_TYPE C0402
J 0
(475 4425);
DISPLAY 0.638298 (475 4425);
FORCEPROP 1 LAST $LOCATION C302
J 0
(475 4725);
DISPLAY 0.638298 (475 4725);
FORCEPROP 1 LASTPIN (425 4725) $PN 1
J 0
(435 4705);
DISPLAY 0.787234 (435 4705);
FORCEPROP 1 LASTPIN (425 4525) $PN 2
J 0
(435 4505);
DISPLAY 0.787234 (435 4505);
FORCEPROP 2 LAST CDS_LIB pure_quanta
J 0
(425 4625);
PAINT MONO (425 4625);
DISPLAY INVISIBLE (425 4625);
FORCEPROP 1 LAST $LOCATION C302
J 0
(475 4825);
DISPLAY 1.021277 (475 4825);
DISPLAY INVISIBLE (475 4825);
FORCEPROP 2 LAST CDS_LOCATION C302
J 0
(475 4825);
DISPLAY 1.021277 (475 4825);
DISPLAY INVISIBLE (475 4825);
FORCEPROP 2 LAST $SEC 1
J 0
(475 4825);
DISPLAY 0.680851 (475 4825);
PAINT MONO (475 4825);
DISPLAY INVISIBLE (475 4825);
FORCEPROP 2 LAST CDS_SEC 1
J 0
(475 4825);
DISPLAY 1.021277 (475 4825);
DISPLAY INVISIBLE (475 4825);
FORCEPROP 1 LAST PATH I117
J 0
(475 4775);
DISPLAY 0.978723 (475 4775);
PAINT WHITE (475 4775);
DISPLAY INVISIBLE (475 4775);
FORCEADD Q_CAP..1
(875 4625);
FORCEPROP 1 LAST PART_NUMBER CH622KMEB01
J 0
(925 4475);
DISPLAY 0.638298 (925 4475);
DISPLAY INVISIBLE (925 4475);
FORCEPROP 1 LAST TOLERANCE 20%
J 0
(925 4575);
DISPLAY 0.638298 (925 4575);
FORCEPROP 1 LAST VOLTAGE 4V
J 0
(925 4625);
DISPLAY 0.638298 (925 4625);
FORCEPROP 1 LAST MATERIAL X6S
J 0
(925 4525);
DISPLAY 0.638298 (925 4525);
FORCEPROP 1 LAST VALUE 22UF
J 0
(925 4675);
DISPLAY 0.638298 (925 4675);
FORCEPROP 1 LAST PACK_TYPE C0402
J 0
(925 4425);
DISPLAY 0.638298 (925 4425);
FORCEPROP 1 LAST $LOCATION C306
J 0
(925 4725);
DISPLAY 0.638298 (925 4725);
FORCEPROP 1 LASTPIN (875 4725) $PN 1
J 0
(885 4705);
DISPLAY 0.787234 (885 4705);
FORCEPROP 1 LASTPIN (875 4525) $PN 2
J 0
(885 4505);
DISPLAY 0.787234 (885 4505);
FORCEPROP 2 LAST CDS_LIB pure_quanta
J 0
(875 4625);
PAINT MONO (875 4625);
DISPLAY INVISIBLE (875 4625);
FORCEPROP 1 LAST $LOCATION C306
J 0
(925 4825);
DISPLAY 1.021277 (925 4825);
DISPLAY INVISIBLE (925 4825);
FORCEPROP 2 LAST CDS_LOCATION C306
J 0
(925 4825);
DISPLAY 1.021277 (925 4825);
DISPLAY INVISIBLE (925 4825);
FORCEPROP 2 LAST $SEC 1
J 0
(925 4825);
DISPLAY 0.680851 (925 4825);
PAINT MONO (925 4825);
DISPLAY INVISIBLE (925 4825);
FORCEPROP 2 LAST CDS_SEC 1
J 0
(925 4825);
DISPLAY 1.021277 (925 4825);
DISPLAY INVISIBLE (925 4825);
FORCEPROP 1 LAST PATH I118
J 0
(925 4775);
DISPLAY 0.978723 (925 4775);
PAINT WHITE (925 4775);
DISPLAY INVISIBLE (925 4775);
FORCEADD Q_CAP..1
(-1375 5400);
FORCEPROP 1 LAST PART_NUMBER CH622KMEB01
J 0
(-1325 5250);
DISPLAY 0.638298 (-1325 5250);
DISPLAY INVISIBLE (-1325 5250);
FORCEPROP 1 LAST VOLTAGE 4V
J 0
(-1325 5400);
DISPLAY 0.638298 (-1325 5400);
FORCEPROP 1 LAST PACK_TYPE C0402
J 0
(-1325 5200);
DISPLAY 0.638298 (-1325 5200);
FORCEPROP 1 LAST MATERIAL X6S
J 0
(-1325 5300);
DISPLAY 0.638298 (-1325 5300);
FORCEPROP 1 LAST VALUE 22UF
J 0
(-1325 5450);
DISPLAY 0.638298 (-1325 5450);
FORCEPROP 1 LAST TOLERANCE 20%
J 0
(-1325 5350);
DISPLAY 0.638298 (-1325 5350);
FORCEPROP 1 LAST $LOCATION C285
J 0
(-1325 5500);
DISPLAY 0.638298 (-1325 5500);
FORCEPROP 1 LASTPIN (-1375 5500) $PN 1
J 0
(-1365 5480);
DISPLAY 0.787234 (-1365 5480);
FORCEPROP 1 LASTPIN (-1375 5300) $PN 2
J 0
(-1365 5280);
DISPLAY 0.787234 (-1365 5280);
FORCEPROP 2 LAST CDS_LIB pure_quanta
J 0
(-1375 5400);
PAINT MONO (-1375 5400);
DISPLAY INVISIBLE (-1375 5400);
FORCEPROP 1 LAST $LOCATION C285
J 0
(-1325 5600);
DISPLAY 1.021277 (-1325 5600);
DISPLAY INVISIBLE (-1325 5600);
FORCEPROP 2 LAST CDS_LOCATION C285
J 0
(-1325 5600);
DISPLAY 1.021277 (-1325 5600);
DISPLAY INVISIBLE (-1325 5600);
FORCEPROP 2 LAST $SEC 1
J 0
(-1325 5600);
DISPLAY 0.680851 (-1325 5600);
PAINT MONO (-1325 5600);
DISPLAY INVISIBLE (-1325 5600);
FORCEPROP 2 LAST CDS_SEC 1
J 0
(-1325 5600);
DISPLAY 1.021277 (-1325 5600);
DISPLAY INVISIBLE (-1325 5600);
FORCEPROP 1 LAST PATH I119
J 0
(-1325 5550);
DISPLAY 0.978723 (-1325 5550);
PAINT WHITE (-1325 5550);
DISPLAY INVISIBLE (-1325 5550);
FORCEADD UNIVERSAL_POWER..1
(-7250 4125);
FORCEPROP 3 LASTPIN (-7250 4075) SIG_NAME PVCCIN_CPU1\g
J 0
(-7240 4085);
DISPLAY 0.659574 (-7240 4085);
PAINT MONO (-7240 4085);
DISPLAY INVISIBLE (-7240 4085);
FORCEPROP 1 LAST HDL_POWER PVCCIN_CPU1
J 1
(-7050 4175);
DISPLAY 0.872340 (-7050 4175);
PAINT GREEN (-7050 4175);
FORCEPROP 2 LAST CDS_LIB logical_power
J 0
(-7250 4125);
DISPLAY INVISIBLE (-7250 4125);
FORCEPROP 1 LAST PATH I12
J 0
(-7200 4150);
DISPLAY 0.872340 (-7200 4150);
PAINT AQUA (-7200 4150);
DISPLAY INVISIBLE (-7200 4150);
FORCEADD Q_CAP..1
(-925 5400);
FORCEPROP 1 LAST PART_NUMBER CH622KMEB01
J 0
(-875 5250);
DISPLAY 0.638298 (-875 5250);
DISPLAY INVISIBLE (-875 5250);
FORCEPROP 1 LAST VOLTAGE 4V
J 0
(-875 5400);
DISPLAY 0.638298 (-875 5400);
FORCEPROP 1 LAST PACK_TYPE C0402
J 0
(-875 5200);
DISPLAY 0.638298 (-875 5200);
FORCEPROP 1 LAST MATERIAL X6S
J 0
(-875 5300);
DISPLAY 0.638298 (-875 5300);
FORCEPROP 1 LAST VALUE 22UF
J 0
(-875 5450);
DISPLAY 0.638298 (-875 5450);
FORCEPROP 1 LAST TOLERANCE 20%
J 0
(-875 5350);
DISPLAY 0.638298 (-875 5350);
FORCEPROP 1 LAST $LOCATION C289
J 0
(-875 5500);
DISPLAY 0.638298 (-875 5500);
FORCEPROP 1 LASTPIN (-925 5500) $PN 1
J 0
(-915 5480);
DISPLAY 0.787234 (-915 5480);
FORCEPROP 1 LASTPIN (-925 5300) $PN 2
J 0
(-915 5280);
DISPLAY 0.787234 (-915 5280);
FORCEPROP 2 LAST CDS_LIB pure_quanta
J 0
(-925 5400);
PAINT MONO (-925 5400);
DISPLAY INVISIBLE (-925 5400);
FORCEPROP 1 LAST $LOCATION C289
J 0
(-875 5600);
DISPLAY 1.021277 (-875 5600);
DISPLAY INVISIBLE (-875 5600);
FORCEPROP 2 LAST CDS_LOCATION C289
J 0
(-875 5600);
DISPLAY 1.021277 (-875 5600);
DISPLAY INVISIBLE (-875 5600);
FORCEPROP 2 LAST $SEC 1
J 0
(-875 5600);
DISPLAY 0.680851 (-875 5600);
PAINT MONO (-875 5600);
DISPLAY INVISIBLE (-875 5600);
FORCEPROP 2 LAST CDS_SEC 1
J 0
(-875 5600);
DISPLAY 1.021277 (-875 5600);
DISPLAY INVISIBLE (-875 5600);
FORCEPROP 1 LAST PATH I120
J 0
(-875 5550);
DISPLAY 0.978723 (-875 5550);
PAINT WHITE (-875 5550);
DISPLAY INVISIBLE (-875 5550);
FORCEADD Q_CAP..1
(-1400 6150);
FORCEPROP 1 LAST PART_NUMBER CH622KMEB01
J 0
(-1350 6000);
DISPLAY 0.638298 (-1350 6000);
DISPLAY INVISIBLE (-1350 6000);
FORCEPROP 1 LAST TOLERANCE 20%
J 0
(-1350 6100);
DISPLAY 0.638298 (-1350 6100);
FORCEPROP 1 LAST VALUE 22UF
J 0
(-1350 6200);
DISPLAY 0.638298 (-1350 6200);
FORCEPROP 1 LAST VOLTAGE 4V
J 0
(-1350 6150);
DISPLAY 0.638298 (-1350 6150);
FORCEPROP 1 LAST MATERIAL X6S
J 0
(-1350 6050);
DISPLAY 0.638298 (-1350 6050);
FORCEPROP 1 LAST PACK_TYPE C0402
J 0
(-1350 5950);
DISPLAY 0.638298 (-1350 5950);
FORCEPROP 1 LAST $LOCATION C284
J 0
(-1350 6250);
DISPLAY 0.638298 (-1350 6250);
FORCEPROP 1 LASTPIN (-1400 6250) $PN 1
J 0
(-1390 6230);
DISPLAY 0.787234 (-1390 6230);
FORCEPROP 1 LASTPIN (-1400 6050) $PN 2
J 0
(-1390 6030);
DISPLAY 0.787234 (-1390 6030);
FORCEPROP 2 LAST CDS_LIB pure_quanta
J 0
(-1400 6150);
PAINT MONO (-1400 6150);
DISPLAY INVISIBLE (-1400 6150);
FORCEPROP 1 LAST $LOCATION C284
J 0
(-1350 6350);
DISPLAY 1.021277 (-1350 6350);
DISPLAY INVISIBLE (-1350 6350);
FORCEPROP 2 LAST CDS_LOCATION C284
J 0
(-1350 6350);
DISPLAY 1.021277 (-1350 6350);
DISPLAY INVISIBLE (-1350 6350);
FORCEPROP 2 LAST $SEC 1
J 0
(-1350 6350);
DISPLAY 0.680851 (-1350 6350);
PAINT MONO (-1350 6350);
DISPLAY INVISIBLE (-1350 6350);
FORCEPROP 2 LAST CDS_SEC 1
J 0
(-1350 6350);
DISPLAY 1.021277 (-1350 6350);
DISPLAY INVISIBLE (-1350 6350);
FORCEPROP 1 LAST PATH I121
J 0
(-1350 6300);
DISPLAY 0.978723 (-1350 6300);
PAINT WHITE (-1350 6300);
DISPLAY INVISIBLE (-1350 6300);
FORCEADD Q_CAP..1
(-1400 6925);
FORCEPROP 1 LAST PART_NUMBER CH622KMEB01
J 0
(-1350 6775);
DISPLAY 0.638298 (-1350 6775);
DISPLAY INVISIBLE (-1350 6775);
FORCEPROP 1 LAST VOLTAGE 4V
J 0
(-1350 6925);
DISPLAY 0.638298 (-1350 6925);
FORCEPROP 1 LAST TOLERANCE 20%
J 0
(-1350 6875);
DISPLAY 0.638298 (-1350 6875);
FORCEPROP 1 LAST PACK_TYPE C0402
J 0
(-1350 6725);
DISPLAY 0.638298 (-1350 6725);
FORCEPROP 1 LAST MATERIAL X6S
J 0
(-1350 6825);
DISPLAY 0.638298 (-1350 6825);
FORCEPROP 1 LAST VALUE 22UF
J 0
(-1350 6975);
DISPLAY 0.638298 (-1350 6975);
FORCEPROP 1 LAST $LOCATION C283
J 0
(-1350 7025);
DISPLAY 0.638298 (-1350 7025);
FORCEPROP 1 LASTPIN (-1400 7025) $PN 1
J 0
(-1390 7005);
DISPLAY 0.787234 (-1390 7005);
FORCEPROP 1 LASTPIN (-1400 6825) $PN 2
J 0
(-1390 6805);
DISPLAY 0.787234 (-1390 6805);
FORCEPROP 2 LAST CDS_LIB pure_quanta
J 0
(-1400 6925);
PAINT MONO (-1400 6925);
DISPLAY INVISIBLE (-1400 6925);
FORCEPROP 1 LAST $LOCATION C283
J 0
(-1350 7125);
DISPLAY 1.021277 (-1350 7125);
DISPLAY INVISIBLE (-1350 7125);
FORCEPROP 2 LAST CDS_LOCATION C283
J 0
(-1350 7125);
DISPLAY 1.021277 (-1350 7125);
DISPLAY INVISIBLE (-1350 7125);
FORCEPROP 2 LAST $SEC 1
J 0
(-1350 7125);
DISPLAY 0.680851 (-1350 7125);
PAINT MONO (-1350 7125);
DISPLAY INVISIBLE (-1350 7125);
FORCEPROP 2 LAST CDS_SEC 1
J 0
(-1350 7125);
DISPLAY 1.021277 (-1350 7125);
DISPLAY INVISIBLE (-1350 7125);
FORCEPROP 1 LAST PATH I122
J 0
(-1350 7075);
DISPLAY 0.978723 (-1350 7075);
PAINT WHITE (-1350 7075);
DISPLAY INVISIBLE (-1350 7075);
FORCEADD Q_CAP..1
(-950 6150);
FORCEPROP 1 LAST PART_NUMBER CH622KMEB01
J 0
(-900 6000);
DISPLAY 0.638298 (-900 6000);
DISPLAY INVISIBLE (-900 6000);
FORCEPROP 1 LAST TOLERANCE 20%
J 0
(-900 6100);
DISPLAY 0.638298 (-900 6100);
FORCEPROP 1 LAST VOLTAGE 4V
J 0
(-900 6150);
DISPLAY 0.638298 (-900 6150);
FORCEPROP 1 LAST VALUE 22UF
J 0
(-900 6200);
DISPLAY 0.638298 (-900 6200);
FORCEPROP 1 LAST MATERIAL X6S
J 0
(-900 6050);
DISPLAY 0.638298 (-900 6050);
FORCEPROP 1 LAST PACK_TYPE C0402
J 0
(-900 5950);
DISPLAY 0.638298 (-900 5950);
FORCEPROP 1 LAST $LOCATION C288
J 0
(-900 6250);
DISPLAY 0.638298 (-900 6250);
FORCEPROP 1 LASTPIN (-950 6250) $PN 1
J 0
(-940 6230);
DISPLAY 0.787234 (-940 6230);
FORCEPROP 1 LASTPIN (-950 6050) $PN 2
J 0
(-940 6030);
DISPLAY 0.787234 (-940 6030);
FORCEPROP 2 LAST CDS_LIB pure_quanta
J 0
(-950 6150);
PAINT MONO (-950 6150);
DISPLAY INVISIBLE (-950 6150);
FORCEPROP 1 LAST $LOCATION C288
J 0
(-900 6350);
DISPLAY 1.021277 (-900 6350);
DISPLAY INVISIBLE (-900 6350);
FORCEPROP 2 LAST CDS_LOCATION C288
J 0
(-900 6350);
DISPLAY 1.021277 (-900 6350);
DISPLAY INVISIBLE (-900 6350);
FORCEPROP 2 LAST $SEC 1
J 0
(-900 6350);
DISPLAY 0.680851 (-900 6350);
PAINT MONO (-900 6350);
DISPLAY INVISIBLE (-900 6350);
FORCEPROP 2 LAST CDS_SEC 1
J 0
(-900 6350);
DISPLAY 1.021277 (-900 6350);
DISPLAY INVISIBLE (-900 6350);
FORCEPROP 1 LAST PATH I123
J 0
(-900 6300);
DISPLAY 0.978723 (-900 6300);
PAINT WHITE (-900 6300);
DISPLAY INVISIBLE (-900 6300);
FORCEADD Q_CAP..1
(-950 6925);
FORCEPROP 1 LAST PART_NUMBER CH622KMEB01
J 0
(-900 6775);
DISPLAY 0.638298 (-900 6775);
DISPLAY INVISIBLE (-900 6775);
FORCEPROP 1 LAST TOLERANCE 20%
J 0
(-900 6875);
DISPLAY 0.638298 (-900 6875);
FORCEPROP 1 LAST VOLTAGE 4V
J 0
(-900 6925);
DISPLAY 0.638298 (-900 6925);
FORCEPROP 1 LAST PACK_TYPE C0402
J 0
(-900 6725);
DISPLAY 0.638298 (-900 6725);
FORCEPROP 1 LAST MATERIAL X6S
J 0
(-900 6825);
DISPLAY 0.638298 (-900 6825);
FORCEPROP 1 LAST VALUE 22UF
J 0
(-900 6975);
DISPLAY 0.638298 (-900 6975);
FORCEPROP 1 LAST $LOCATION C287
J 0
(-900 7025);
DISPLAY 0.638298 (-900 7025);
FORCEPROP 1 LASTPIN (-950 7025) $PN 1
J 0
(-940 7005);
DISPLAY 0.787234 (-940 7005);
FORCEPROP 1 LASTPIN (-950 6825) $PN 2
J 0
(-940 6805);
DISPLAY 0.787234 (-940 6805);
FORCEPROP 2 LAST CDS_LIB pure_quanta
J 0
(-950 6925);
PAINT MONO (-950 6925);
DISPLAY INVISIBLE (-950 6925);
FORCEPROP 1 LAST $LOCATION C287
J 0
(-900 7125);
DISPLAY 1.021277 (-900 7125);
DISPLAY INVISIBLE (-900 7125);
FORCEPROP 2 LAST CDS_LOCATION C287
J 0
(-900 7125);
DISPLAY 1.021277 (-900 7125);
DISPLAY INVISIBLE (-900 7125);
FORCEPROP 2 LAST $SEC 1
J 0
(-900 7125);
DISPLAY 0.680851 (-900 7125);
PAINT MONO (-900 7125);
DISPLAY INVISIBLE (-900 7125);
FORCEPROP 2 LAST CDS_SEC 1
J 0
(-900 7125);
DISPLAY 1.021277 (-900 7125);
DISPLAY INVISIBLE (-900 7125);
FORCEPROP 1 LAST PATH I124
J 0
(-900 7075);
DISPLAY 0.978723 (-900 7075);
PAINT WHITE (-900 7075);
DISPLAY INVISIBLE (-900 7075);
FORCEADD Q_CAP..1
(-475 5400);
FORCEPROP 1 LAST PART_NUMBER CH622KMEB01
J 0
(-425 5250);
DISPLAY 0.638298 (-425 5250);
DISPLAY INVISIBLE (-425 5250);
FORCEPROP 1 LAST VOLTAGE 4V
J 0
(-425 5400);
DISPLAY 0.638298 (-425 5400);
FORCEPROP 1 LAST PACK_TYPE C0402
J 0
(-425 5200);
DISPLAY 0.638298 (-425 5200);
FORCEPROP 1 LAST MATERIAL X6S
J 0
(-425 5300);
DISPLAY 0.638298 (-425 5300);
FORCEPROP 1 LAST TOLERANCE 20%
J 0
(-425 5350);
DISPLAY 0.638298 (-425 5350);
FORCEPROP 1 LAST VALUE 22UF
J 0
(-425 5450);
DISPLAY 0.638298 (-425 5450);
FORCEPROP 1 LAST $LOCATION C293
J 0
(-425 5500);
DISPLAY 0.638298 (-425 5500);
FORCEPROP 1 LASTPIN (-475 5500) $PN 1
J 0
(-465 5480);
DISPLAY 0.787234 (-465 5480);
FORCEPROP 1 LASTPIN (-475 5300) $PN 2
J 0
(-465 5280);
DISPLAY 0.787234 (-465 5280);
FORCEPROP 2 LAST CDS_LIB pure_quanta
J 0
(-475 5400);
PAINT MONO (-475 5400);
DISPLAY INVISIBLE (-475 5400);
FORCEPROP 1 LAST $LOCATION C293
J 0
(-425 5600);
DISPLAY 1.021277 (-425 5600);
DISPLAY INVISIBLE (-425 5600);
FORCEPROP 2 LAST CDS_LOCATION C293
J 0
(-425 5600);
DISPLAY 1.021277 (-425 5600);
DISPLAY INVISIBLE (-425 5600);
FORCEPROP 2 LAST $SEC 1
J 0
(-425 5600);
DISPLAY 0.680851 (-425 5600);
PAINT MONO (-425 5600);
DISPLAY INVISIBLE (-425 5600);
FORCEPROP 2 LAST CDS_SEC 1
J 0
(-425 5600);
DISPLAY 1.021277 (-425 5600);
DISPLAY INVISIBLE (-425 5600);
FORCEPROP 1 LAST PATH I125
J 0
(-425 5550);
DISPLAY 0.978723 (-425 5550);
PAINT WHITE (-425 5550);
DISPLAY INVISIBLE (-425 5550);
FORCEADD Q_CAP..1
(-25 5400);
FORCEPROP 1 LAST PART_NUMBER CH622KMEB01
J 0
(25 5250);
DISPLAY 0.638298 (25 5250);
DISPLAY INVISIBLE (25 5250);
FORCEPROP 1 LAST VOLTAGE 4V
J 0
(25 5400);
DISPLAY 0.638298 (25 5400);
FORCEPROP 1 LAST PACK_TYPE C0402
J 0
(25 5200);
DISPLAY 0.638298 (25 5200);
FORCEPROP 1 LAST MATERIAL X6S
J 0
(25 5300);
DISPLAY 0.638298 (25 5300);
FORCEPROP 1 LAST TOLERANCE 20%
J 0
(25 5350);
DISPLAY 0.638298 (25 5350);
FORCEPROP 1 LAST VALUE 22UF
J 0
(25 5450);
DISPLAY 0.638298 (25 5450);
FORCEPROP 1 LAST $LOCATION C297
J 0
(25 5500);
DISPLAY 0.638298 (25 5500);
FORCEPROP 1 LASTPIN (-25 5500) $PN 1
J 0
(-15 5480);
DISPLAY 0.787234 (-15 5480);
FORCEPROP 1 LASTPIN (-25 5300) $PN 2
J 0
(-15 5280);
DISPLAY 0.787234 (-15 5280);
FORCEPROP 2 LAST CDS_LIB pure_quanta
J 0
(-25 5400);
PAINT MONO (-25 5400);
DISPLAY INVISIBLE (-25 5400);
FORCEPROP 1 LAST $LOCATION C297
J 0
(25 5600);
DISPLAY 1.021277 (25 5600);
DISPLAY INVISIBLE (25 5600);
FORCEPROP 2 LAST CDS_LOCATION C297
J 0
(25 5600);
DISPLAY 1.021277 (25 5600);
DISPLAY INVISIBLE (25 5600);
FORCEPROP 2 LAST $SEC 1
J 0
(25 5600);
DISPLAY 0.680851 (25 5600);
PAINT MONO (25 5600);
DISPLAY INVISIBLE (25 5600);
FORCEPROP 2 LAST CDS_SEC 1
J 0
(25 5600);
DISPLAY 1.021277 (25 5600);
DISPLAY INVISIBLE (25 5600);
FORCEPROP 1 LAST PATH I126
J 0
(25 5550);
DISPLAY 0.978723 (25 5550);
PAINT WHITE (25 5550);
DISPLAY INVISIBLE (25 5550);
FORCEADD Q_CAP..1
(-500 6150);
FORCEPROP 1 LAST PART_NUMBER CH622KMEB01
J 0
(-450 6000);
DISPLAY 0.638298 (-450 6000);
DISPLAY INVISIBLE (-450 6000);
FORCEPROP 1 LAST VOLTAGE 4V
J 0
(-450 6150);
DISPLAY 0.638298 (-450 6150);
FORCEPROP 1 LAST VALUE 22UF
J 0
(-450 6200);
DISPLAY 0.638298 (-450 6200);
FORCEPROP 1 LAST TOLERANCE 20%
J 0
(-450 6100);
DISPLAY 0.638298 (-450 6100);
FORCEPROP 1 LAST PACK_TYPE C0402
J 0
(-450 5950);
DISPLAY 0.638298 (-450 5950);
FORCEPROP 1 LAST MATERIAL X6S
J 0
(-450 6050);
DISPLAY 0.638298 (-450 6050);
FORCEPROP 1 LAST $LOCATION C292
J 0
(-450 6250);
DISPLAY 0.638298 (-450 6250);
FORCEPROP 1 LASTPIN (-500 6250) $PN 1
J 0
(-490 6230);
DISPLAY 0.787234 (-490 6230);
FORCEPROP 1 LASTPIN (-500 6050) $PN 2
J 0
(-490 6030);
DISPLAY 0.787234 (-490 6030);
FORCEPROP 2 LAST CDS_LIB pure_quanta
J 0
(-500 6150);
PAINT MONO (-500 6150);
DISPLAY INVISIBLE (-500 6150);
FORCEPROP 1 LAST $LOCATION C292
J 0
(-450 6350);
DISPLAY 1.021277 (-450 6350);
DISPLAY INVISIBLE (-450 6350);
FORCEPROP 2 LAST CDS_LOCATION C292
J 0
(-450 6350);
DISPLAY 1.021277 (-450 6350);
DISPLAY INVISIBLE (-450 6350);
FORCEPROP 2 LAST $SEC 1
J 0
(-450 6350);
DISPLAY 0.680851 (-450 6350);
PAINT MONO (-450 6350);
DISPLAY INVISIBLE (-450 6350);
FORCEPROP 2 LAST CDS_SEC 1
J 0
(-450 6350);
DISPLAY 1.021277 (-450 6350);
DISPLAY INVISIBLE (-450 6350);
FORCEPROP 1 LAST PATH I127
J 0
(-450 6300);
DISPLAY 0.978723 (-450 6300);
PAINT WHITE (-450 6300);
DISPLAY INVISIBLE (-450 6300);
FORCEADD Q_CAP..1
(-500 6925);
FORCEPROP 1 LAST PART_NUMBER CH622KMEB01
J 0
(-450 6775);
DISPLAY 0.638298 (-450 6775);
DISPLAY INVISIBLE (-450 6775);
FORCEPROP 1 LAST TOLERANCE 20%
J 0
(-450 6875);
DISPLAY 0.638298 (-450 6875);
FORCEPROP 1 LAST VOLTAGE 4V
J 0
(-450 6925);
DISPLAY 0.638298 (-450 6925);
FORCEPROP 1 LAST PACK_TYPE C0402
J 0
(-450 6725);
DISPLAY 0.638298 (-450 6725);
FORCEPROP 1 LAST VALUE 22UF
J 0
(-450 6975);
DISPLAY 0.638298 (-450 6975);
FORCEPROP 1 LAST MATERIAL X6S
J 0
(-450 6825);
DISPLAY 0.638298 (-450 6825);
FORCEPROP 1 LAST $LOCATION C291
J 0
(-450 7025);
DISPLAY 0.638298 (-450 7025);
FORCEPROP 1 LASTPIN (-500 7025) $PN 1
J 0
(-490 7005);
DISPLAY 0.787234 (-490 7005);
FORCEPROP 1 LASTPIN (-500 6825) $PN 2
J 0
(-490 6805);
DISPLAY 0.787234 (-490 6805);
FORCEPROP 2 LAST CDS_LIB pure_quanta
J 0
(-500 6925);
PAINT MONO (-500 6925);
DISPLAY INVISIBLE (-500 6925);
FORCEPROP 1 LAST $LOCATION C291
J 0
(-450 7125);
DISPLAY 1.021277 (-450 7125);
DISPLAY INVISIBLE (-450 7125);
FORCEPROP 2 LAST CDS_LOCATION C291
J 0
(-450 7125);
DISPLAY 1.021277 (-450 7125);
DISPLAY INVISIBLE (-450 7125);
FORCEPROP 2 LAST $SEC 1
J 0
(-450 7125);
DISPLAY 0.680851 (-450 7125);
PAINT MONO (-450 7125);
DISPLAY INVISIBLE (-450 7125);
FORCEPROP 2 LAST CDS_SEC 1
J 0
(-450 7125);
DISPLAY 1.021277 (-450 7125);
DISPLAY INVISIBLE (-450 7125);
FORCEPROP 1 LAST PATH I128
J 0
(-450 7075);
DISPLAY 0.978723 (-450 7075);
PAINT WHITE (-450 7075);
DISPLAY INVISIBLE (-450 7075);
FORCEADD Q_CAP..1
(-50 6150);
FORCEPROP 1 LAST PART_NUMBER CH622KMEB01
J 0
(0 6000);
DISPLAY 0.638298 (0 6000);
DISPLAY INVISIBLE (0 6000);
FORCEPROP 1 LAST VOLTAGE 4V
J 0
(0 6150);
DISPLAY 0.638298 (0 6150);
FORCEPROP 1 LAST VALUE 22UF
J 0
(0 6200);
DISPLAY 0.638298 (0 6200);
FORCEPROP 1 LAST TOLERANCE 20%
J 0
(0 6100);
DISPLAY 0.638298 (0 6100);
FORCEPROP 1 LAST MATERIAL X6S
J 0
(0 6050);
DISPLAY 0.638298 (0 6050);
FORCEPROP 1 LAST PACK_TYPE C0402
J 0
(0 5950);
DISPLAY 0.638298 (0 5950);
FORCEPROP 1 LAST $LOCATION C296
J 0
(0 6250);
DISPLAY 0.638298 (0 6250);
FORCEPROP 1 LASTPIN (-50 6250) $PN 1
J 0
(-40 6230);
DISPLAY 0.787234 (-40 6230);
FORCEPROP 1 LASTPIN (-50 6050) $PN 2
J 0
(-40 6030);
DISPLAY 0.787234 (-40 6030);
FORCEPROP 2 LAST CDS_LIB pure_quanta
J 0
(-50 6150);
PAINT MONO (-50 6150);
DISPLAY INVISIBLE (-50 6150);
FORCEPROP 1 LAST $LOCATION C296
J 0
(0 6350);
DISPLAY 1.021277 (0 6350);
DISPLAY INVISIBLE (0 6350);
FORCEPROP 2 LAST CDS_LOCATION C296
J 0
(0 6350);
DISPLAY 1.021277 (0 6350);
DISPLAY INVISIBLE (0 6350);
FORCEPROP 2 LAST $SEC 1
J 0
(0 6350);
DISPLAY 0.680851 (0 6350);
PAINT MONO (0 6350);
DISPLAY INVISIBLE (0 6350);
FORCEPROP 2 LAST CDS_SEC 1
J 0
(0 6350);
DISPLAY 1.021277 (0 6350);
DISPLAY INVISIBLE (0 6350);
FORCEPROP 1 LAST PATH I129
J 0
(0 6300);
DISPLAY 0.978723 (0 6300);
PAINT WHITE (0 6300);
DISPLAY INVISIBLE (0 6300);
FORCEADD Q_CAP..1
(-7250 4625);
FORCEPROP 1 LAST PART_NUMBER CH6101MEB03
J 0
(-7200 4475);
DISPLAY 0.638298 (-7200 4475);
DISPLAY INVISIBLE (-7200 4475);
FORCEPROP 1 LAST VOLTAGE 6.3V
J 0
(-7200 4625);
DISPLAY 0.638298 (-7200 4625);
FORCEPROP 1 LAST VALUE 10UF
J 0
(-7200 4675);
DISPLAY 0.638298 (-7200 4675);
FORCEPROP 1 LAST PACK_TYPE C0402
J 0
(-7200 4425);
DISPLAY 0.638298 (-7200 4425);
FORCEPROP 1 LAST MATERIAL X6S
J 0
(-7200 4525);
DISPLAY 0.638298 (-7200 4525);
FORCEPROP 1 LAST TOLERANCE 20%
J 0
(-7200 4575);
DISPLAY 0.638298 (-7200 4575);
FORCEPROP 1 LAST $LOCATION C224
J 0
(-7200 4725);
DISPLAY 0.638298 (-7200 4725);
FORCEPROP 1 LASTPIN (-7250 4725) $PN 1
J 0
(-7240 4705);
DISPLAY 0.787234 (-7240 4705);
FORCEPROP 1 LASTPIN (-7250 4525) $PN 2
J 0
(-7240 4505);
DISPLAY 0.787234 (-7240 4505);
FORCEPROP 2 LAST CDS_LIB pure_quanta
J 0
(-7250 4625);
PAINT MONO (-7250 4625);
DISPLAY INVISIBLE (-7250 4625);
FORCEPROP 1 LAST $LOCATION C224
J 0
(-7200 4825);
DISPLAY 1.021277 (-7200 4825);
DISPLAY INVISIBLE (-7200 4825);
FORCEPROP 2 LAST CDS_LOCATION C224
J 0
(-7200 4825);
DISPLAY 1.021277 (-7200 4825);
DISPLAY INVISIBLE (-7200 4825);
FORCEPROP 2 LAST $SEC 1
J 0
(-7200 4825);
DISPLAY 0.680851 (-7200 4825);
PAINT MONO (-7200 4825);
DISPLAY INVISIBLE (-7200 4825);
FORCEPROP 2 LAST CDS_SEC 1
J 0
(-7200 4825);
DISPLAY 1.021277 (-7200 4825);
DISPLAY INVISIBLE (-7200 4825);
FORCEPROP 1 LAST PATH I13
J 0
(-7200 4775);
DISPLAY 0.978723 (-7200 4775);
PAINT WHITE (-7200 4775);
DISPLAY INVISIBLE (-7200 4775);
FORCEADD Q_CAP..1
(-50 6925);
FORCEPROP 1 LAST PART_NUMBER CH622KMEB01
J 0
(0 6775);
DISPLAY 0.638298 (0 6775);
DISPLAY INVISIBLE (0 6775);
FORCEPROP 1 LAST VOLTAGE 4V
J 0
(0 6925);
DISPLAY 0.638298 (0 6925);
FORCEPROP 1 LAST TOLERANCE 20%
J 0
(0 6875);
DISPLAY 0.638298 (0 6875);
FORCEPROP 1 LAST PACK_TYPE C0402
J 0
(0 6725);
DISPLAY 0.638298 (0 6725);
FORCEPROP 1 LAST MATERIAL X6S
J 0
(0 6825);
DISPLAY 0.638298 (0 6825);
FORCEPROP 1 LAST VALUE 22UF
J 0
(0 6975);
DISPLAY 0.638298 (0 6975);
FORCEPROP 1 LAST $LOCATION C295
J 0
(0 7025);
DISPLAY 0.638298 (0 7025);
FORCEPROP 1 LASTPIN (-50 7025) $PN 1
J 0
(-40 7005);
DISPLAY 0.787234 (-40 7005);
FORCEPROP 1 LASTPIN (-50 6825) $PN 2
J 0
(-40 6805);
DISPLAY 0.787234 (-40 6805);
FORCEPROP 2 LAST CDS_LIB pure_quanta
J 0
(-50 6925);
PAINT MONO (-50 6925);
DISPLAY INVISIBLE (-50 6925);
FORCEPROP 1 LAST $LOCATION C295
J 0
(0 7125);
DISPLAY 1.021277 (0 7125);
DISPLAY INVISIBLE (0 7125);
FORCEPROP 2 LAST CDS_LOCATION C295
J 0
(0 7125);
DISPLAY 1.021277 (0 7125);
DISPLAY INVISIBLE (0 7125);
FORCEPROP 2 LAST $SEC 1
J 0
(0 7125);
DISPLAY 0.680851 (0 7125);
PAINT MONO (0 7125);
DISPLAY INVISIBLE (0 7125);
FORCEPROP 2 LAST CDS_SEC 1
J 0
(0 7125);
DISPLAY 1.021277 (0 7125);
DISPLAY INVISIBLE (0 7125);
FORCEPROP 1 LAST PATH I130
J 0
(0 7075);
DISPLAY 0.978723 (0 7075);
PAINT WHITE (0 7075);
DISPLAY INVISIBLE (0 7075);
FORCEADD Q_CAP..1
(400 6925);
FORCEPROP 1 LAST PART_NUMBER CH622KMEB01
J 0
(450 6775);
DISPLAY 0.638298 (450 6775);
DISPLAY INVISIBLE (450 6775);
FORCEPROP 1 LAST VOLTAGE 4V
J 0
(450 6925);
DISPLAY 0.638298 (450 6925);
FORCEPROP 1 LAST TOLERANCE 20%
J 0
(450 6875);
DISPLAY 0.638298 (450 6875);
FORCEPROP 1 LAST PACK_TYPE C0402
J 0
(450 6725);
DISPLAY 0.638298 (450 6725);
FORCEPROP 1 LAST MATERIAL X6S
J 0
(450 6825);
DISPLAY 0.638298 (450 6825);
FORCEPROP 1 LAST VALUE 22UF
J 0
(450 6975);
DISPLAY 0.638298 (450 6975);
FORCEPROP 1 LAST $LOCATION C299
J 0
(450 7025);
DISPLAY 0.638298 (450 7025);
FORCEPROP 1 LASTPIN (400 7025) $PN 1
J 0
(410 7005);
DISPLAY 0.787234 (410 7005);
FORCEPROP 1 LASTPIN (400 6825) $PN 2
J 0
(410 6805);
DISPLAY 0.787234 (410 6805);
FORCEPROP 2 LAST CDS_LIB pure_quanta
J 0
(400 6925);
PAINT MONO (400 6925);
DISPLAY INVISIBLE (400 6925);
FORCEPROP 1 LAST $LOCATION C299
J 0
(450 7125);
DISPLAY 1.021277 (450 7125);
DISPLAY INVISIBLE (450 7125);
FORCEPROP 2 LAST CDS_LOCATION C299
J 0
(450 7125);
DISPLAY 1.021277 (450 7125);
DISPLAY INVISIBLE (450 7125);
FORCEPROP 2 LAST $SEC 1
J 0
(450 7125);
DISPLAY 0.680851 (450 7125);
PAINT MONO (450 7125);
DISPLAY INVISIBLE (450 7125);
FORCEPROP 2 LAST CDS_SEC 1
J 0
(450 7125);
DISPLAY 1.021277 (450 7125);
DISPLAY INVISIBLE (450 7125);
FORCEPROP 1 LAST PATH I131
J 0
(450 7075);
DISPLAY 0.978723 (450 7075);
PAINT WHITE (450 7075);
DISPLAY INVISIBLE (450 7075);
FORCEADD Q_CAP..1
(400 6150);
FORCEPROP 1 LAST PART_NUMBER CH622KMEB01
J 0
(450 6000);
DISPLAY 0.638298 (450 6000);
DISPLAY INVISIBLE (450 6000);
FORCEPROP 1 LAST VOLTAGE 4V
J 0
(450 6150);
DISPLAY 0.638298 (450 6150);
FORCEPROP 1 LAST VALUE 22UF
J 0
(450 6200);
DISPLAY 0.638298 (450 6200);
FORCEPROP 1 LAST TOLERANCE 20%
J 0
(450 6100);
DISPLAY 0.638298 (450 6100);
FORCEPROP 1 LAST PACK_TYPE C0402
J 0
(450 5950);
DISPLAY 0.638298 (450 5950);
FORCEPROP 1 LAST MATERIAL X6S
J 0
(450 6050);
DISPLAY 0.638298 (450 6050);
FORCEPROP 1 LAST $LOCATION C300
J 0
(450 6250);
DISPLAY 0.638298 (450 6250);
FORCEPROP 1 LASTPIN (400 6250) $PN 1
J 0
(410 6230);
DISPLAY 0.787234 (410 6230);
FORCEPROP 1 LASTPIN (400 6050) $PN 2
J 0
(410 6030);
DISPLAY 0.787234 (410 6030);
FORCEPROP 2 LAST CDS_LIB pure_quanta
J 0
(400 6150);
PAINT MONO (400 6150);
DISPLAY INVISIBLE (400 6150);
FORCEPROP 1 LAST $LOCATION C300
J 0
(450 6350);
DISPLAY 1.021277 (450 6350);
DISPLAY INVISIBLE (450 6350);
FORCEPROP 2 LAST CDS_LOCATION C300
J 0
(450 6350);
DISPLAY 1.021277 (450 6350);
DISPLAY INVISIBLE (450 6350);
FORCEPROP 2 LAST $SEC 1
J 0
(450 6350);
DISPLAY 0.680851 (450 6350);
PAINT MONO (450 6350);
DISPLAY INVISIBLE (450 6350);
FORCEPROP 2 LAST CDS_SEC 1
J 0
(450 6350);
DISPLAY 1.021277 (450 6350);
DISPLAY INVISIBLE (450 6350);
FORCEPROP 1 LAST PATH I132
J 0
(450 6300);
DISPLAY 0.978723 (450 6300);
PAINT WHITE (450 6300);
DISPLAY INVISIBLE (450 6300);
FORCEADD Q_CAP..1
(425 5400);
FORCEPROP 1 LAST PART_NUMBER CH622KMEB01
J 0
(475 5250);
DISPLAY 0.638298 (475 5250);
DISPLAY INVISIBLE (475 5250);
FORCEPROP 1 LAST VOLTAGE 4V
J 0
(475 5400);
DISPLAY 0.638298 (475 5400);
FORCEPROP 1 LAST PACK_TYPE C0402
J 0
(475 5200);
DISPLAY 0.638298 (475 5200);
FORCEPROP 1 LAST MATERIAL X6S
J 0
(475 5300);
DISPLAY 0.638298 (475 5300);
FORCEPROP 1 LAST TOLERANCE 20%
J 0
(475 5350);
DISPLAY 0.638298 (475 5350);
FORCEPROP 1 LAST VALUE 22UF
J 0
(475 5450);
DISPLAY 0.638298 (475 5450);
FORCEPROP 1 LAST $LOCATION C301
J 0
(475 5500);
DISPLAY 0.638298 (475 5500);
FORCEPROP 1 LASTPIN (425 5500) $PN 1
J 0
(435 5480);
DISPLAY 0.787234 (435 5480);
FORCEPROP 1 LASTPIN (425 5300) $PN 2
J 0
(435 5280);
DISPLAY 0.787234 (435 5280);
FORCEPROP 2 LAST CDS_LIB pure_quanta
J 0
(425 5400);
PAINT MONO (425 5400);
DISPLAY INVISIBLE (425 5400);
FORCEPROP 1 LAST $LOCATION C301
J 0
(475 5600);
DISPLAY 1.021277 (475 5600);
DISPLAY INVISIBLE (475 5600);
FORCEPROP 2 LAST CDS_LOCATION C301
J 0
(475 5600);
DISPLAY 1.021277 (475 5600);
DISPLAY INVISIBLE (475 5600);
FORCEPROP 2 LAST $SEC 1
J 0
(475 5600);
DISPLAY 0.680851 (475 5600);
PAINT MONO (475 5600);
DISPLAY INVISIBLE (475 5600);
FORCEPROP 2 LAST CDS_SEC 1
J 0
(475 5600);
DISPLAY 1.021277 (475 5600);
DISPLAY INVISIBLE (475 5600);
FORCEPROP 1 LAST PATH I133
J 0
(475 5550);
DISPLAY 0.978723 (475 5550);
PAINT WHITE (475 5550);
DISPLAY INVISIBLE (475 5550);
FORCEADD Q_CAP..1
(875 5400);
FORCEPROP 1 LAST PART_NUMBER CH622KMEB01
J 0
(925 5250);
DISPLAY 0.638298 (925 5250);
DISPLAY INVISIBLE (925 5250);
FORCEPROP 1 LAST VOLTAGE 4V
J 0
(925 5400);
DISPLAY 0.638298 (925 5400);
FORCEPROP 1 LAST PACK_TYPE C0402
J 0
(925 5200);
DISPLAY 0.638298 (925 5200);
FORCEPROP 1 LAST MATERIAL X6S
J 0
(925 5300);
DISPLAY 0.638298 (925 5300);
FORCEPROP 1 LAST TOLERANCE 20%
J 0
(925 5350);
DISPLAY 0.638298 (925 5350);
FORCEPROP 1 LAST VALUE 22UF
J 0
(925 5450);
DISPLAY 0.638298 (925 5450);
FORCEPROP 1 LAST $LOCATION C305
J 0
(925 5500);
DISPLAY 0.638298 (925 5500);
FORCEPROP 1 LASTPIN (875 5500) $PN 1
J 0
(885 5480);
DISPLAY 0.787234 (885 5480);
FORCEPROP 1 LASTPIN (875 5300) $PN 2
J 0
(885 5280);
DISPLAY 0.787234 (885 5280);
FORCEPROP 2 LAST CDS_LIB pure_quanta
J 0
(875 5400);
PAINT MONO (875 5400);
DISPLAY INVISIBLE (875 5400);
FORCEPROP 1 LAST $LOCATION C305
J 0
(925 5600);
DISPLAY 1.021277 (925 5600);
DISPLAY INVISIBLE (925 5600);
FORCEPROP 2 LAST CDS_LOCATION C305
J 0
(925 5600);
DISPLAY 1.021277 (925 5600);
DISPLAY INVISIBLE (925 5600);
FORCEPROP 2 LAST $SEC 1
J 0
(925 5600);
DISPLAY 0.680851 (925 5600);
PAINT MONO (925 5600);
DISPLAY INVISIBLE (925 5600);
FORCEPROP 2 LAST CDS_SEC 1
J 0
(925 5600);
DISPLAY 1.021277 (925 5600);
DISPLAY INVISIBLE (925 5600);
FORCEPROP 1 LAST PATH I134
J 0
(925 5550);
DISPLAY 0.978723 (925 5550);
PAINT WHITE (925 5550);
DISPLAY INVISIBLE (925 5550);
FORCEADD UNIVERSAL_GND..1
(1325 5050);
FORCEPROP 3 LASTPIN (1325 5100) SIG_NAME GND\g
J 0
(1335 5110);
DISPLAY 0.659574 (1335 5110);
PAINT MONO (1335 5110);
DISPLAY INVISIBLE (1335 5110);
FORCEPROP 2 LAST CDS_LIB logical_power
J 0
(1325 5050);
PAINT MONO (1325 5050);
DISPLAY INVISIBLE (1325 5050);
FORCEPROP 1 LAST HDL_POWER GND
J 1
(1350 4975);
DISPLAY 0.872340 (1350 4975);
PAINT GREEN (1350 4975);
DISPLAY INVISIBLE (1350 4975);
FORCEPROP 1 LAST PATH I135
J 0
(1400 5050);
DISPLAY 0.872340 (1400 5050);
PAINT AQUA (1400 5050);
DISPLAY INVISIBLE (1400 5050);
FORCEADD Q_CAP..1
(1325 5400);
FORCEPROP 1 LAST PART_NUMBER CH622KMEB01
J 0
(1375 5250);
DISPLAY 0.638298 (1375 5250);
DISPLAY INVISIBLE (1375 5250);
FORCEPROP 1 LAST VOLTAGE 4V
J 0
(1375 5400);
DISPLAY 0.638298 (1375 5400);
FORCEPROP 1 LAST TOLERANCE 20%
J 0
(1375 5350);
DISPLAY 0.638298 (1375 5350);
FORCEPROP 1 LAST MATERIAL X6S
J 0
(1375 5300);
DISPLAY 0.638298 (1375 5300);
FORCEPROP 1 LAST PACK_TYPE C0402
J 0
(1375 5200);
DISPLAY 0.638298 (1375 5200);
FORCEPROP 1 LAST VALUE 22UF
J 0
(1375 5450);
DISPLAY 0.638298 (1375 5450);
FORCEPROP 1 LAST $LOCATION C309
J 0
(1375 5500);
DISPLAY 0.638298 (1375 5500);
FORCEPROP 1 LASTPIN (1325 5500) $PN 1
J 0
(1335 5480);
DISPLAY 0.787234 (1335 5480);
FORCEPROP 1 LASTPIN (1325 5300) $PN 2
J 0
(1335 5280);
DISPLAY 0.787234 (1335 5280);
FORCEPROP 2 LAST CDS_LIB pure_quanta
J 0
(1325 5400);
PAINT MONO (1325 5400);
DISPLAY INVISIBLE (1325 5400);
FORCEPROP 1 LAST $LOCATION C309
J 0
(1375 5600);
DISPLAY 1.021277 (1375 5600);
DISPLAY INVISIBLE (1375 5600);
FORCEPROP 2 LAST CDS_LOCATION C309
J 0
(1375 5600);
DISPLAY 1.021277 (1375 5600);
DISPLAY INVISIBLE (1375 5600);
FORCEPROP 2 LAST $SEC 1
J 0
(1375 5600);
DISPLAY 0.680851 (1375 5600);
PAINT MONO (1375 5600);
DISPLAY INVISIBLE (1375 5600);
FORCEPROP 2 LAST CDS_SEC 1
J 0
(1375 5600);
DISPLAY 1.021277 (1375 5600);
DISPLAY INVISIBLE (1375 5600);
FORCEPROP 1 LAST PATH I136
J 0
(1375 5550);
DISPLAY 0.978723 (1375 5550);
PAINT WHITE (1375 5550);
DISPLAY INVISIBLE (1375 5550);
FORCEADD UNIVERSAL_GND..1
(1300 5800);
FORCEPROP 3 LASTPIN (1300 5850) SIG_NAME GND\g
J 0
(1310 5860);
DISPLAY 0.659574 (1310 5860);
PAINT MONO (1310 5860);
DISPLAY INVISIBLE (1310 5860);
FORCEPROP 2 LAST CDS_LIB logical_power
J 0
(1300 5800);
PAINT MONO (1300 5800);
DISPLAY INVISIBLE (1300 5800);
FORCEPROP 1 LAST HDL_POWER GND
J 1
(1325 5725);
DISPLAY 0.872340 (1325 5725);
PAINT GREEN (1325 5725);
DISPLAY INVISIBLE (1325 5725);
FORCEPROP 1 LAST PATH I137
J 0
(1375 5800);
DISPLAY 0.872340 (1375 5800);
PAINT AQUA (1375 5800);
DISPLAY INVISIBLE (1375 5800);
FORCEADD Q_CAP..1
(850 6150);
FORCEPROP 1 LAST PART_NUMBER CH622KMEB01
J 0
(900 6000);
DISPLAY 0.638298 (900 6000);
DISPLAY INVISIBLE (900 6000);
FORCEPROP 1 LAST VALUE 22UF
J 0
(900 6200);
DISPLAY 0.638298 (900 6200);
FORCEPROP 1 LAST VOLTAGE 4V
J 0
(900 6150);
DISPLAY 0.638298 (900 6150);
FORCEPROP 1 LAST TOLERANCE 20%
J 0
(900 6100);
DISPLAY 0.638298 (900 6100);
FORCEPROP 1 LAST PACK_TYPE C0402
J 0
(900 5950);
DISPLAY 0.638298 (900 5950);
FORCEPROP 1 LAST MATERIAL X6S
J 0
(900 6050);
DISPLAY 0.638298 (900 6050);
FORCEPROP 1 LAST $LOCATION C304
J 0
(900 6250);
DISPLAY 0.638298 (900 6250);
FORCEPROP 1 LASTPIN (850 6250) $PN 1
J 0
(860 6230);
DISPLAY 0.787234 (860 6230);
FORCEPROP 1 LASTPIN (850 6050) $PN 2
J 0
(860 6030);
DISPLAY 0.787234 (860 6030);
FORCEPROP 2 LAST CDS_LIB pure_quanta
J 0
(850 6150);
PAINT MONO (850 6150);
DISPLAY INVISIBLE (850 6150);
FORCEPROP 1 LAST $LOCATION C304
J 0
(900 6350);
DISPLAY 1.021277 (900 6350);
DISPLAY INVISIBLE (900 6350);
FORCEPROP 2 LAST CDS_LOCATION C304
J 0
(900 6350);
DISPLAY 1.021277 (900 6350);
DISPLAY INVISIBLE (900 6350);
FORCEPROP 2 LAST $SEC 1
J 0
(900 6350);
DISPLAY 0.680851 (900 6350);
PAINT MONO (900 6350);
DISPLAY INVISIBLE (900 6350);
FORCEPROP 2 LAST CDS_SEC 1
J 0
(900 6350);
DISPLAY 1.021277 (900 6350);
DISPLAY INVISIBLE (900 6350);
FORCEPROP 1 LAST PATH I138
J 0
(900 6300);
DISPLAY 0.978723 (900 6300);
PAINT WHITE (900 6300);
DISPLAY INVISIBLE (900 6300);
FORCEADD Q_CAP..1
(850 6925);
FORCEPROP 1 LAST PART_NUMBER CH622KMEB01
J 0
(900 6775);
DISPLAY 0.638298 (900 6775);
DISPLAY INVISIBLE (900 6775);
FORCEPROP 1 LAST VOLTAGE 4V
J 0
(900 6925);
DISPLAY 0.638298 (900 6925);
FORCEPROP 1 LAST TOLERANCE 20%
J 0
(900 6875);
DISPLAY 0.638298 (900 6875);
FORCEPROP 1 LAST PACK_TYPE C0402
J 0
(900 6725);
DISPLAY 0.638298 (900 6725);
FORCEPROP 1 LAST MATERIAL X6S
J 0
(900 6825);
DISPLAY 0.638298 (900 6825);
FORCEPROP 1 LAST VALUE 22UF
J 0
(900 6975);
DISPLAY 0.638298 (900 6975);
FORCEPROP 1 LAST $LOCATION C303
J 0
(900 7025);
DISPLAY 0.638298 (900 7025);
FORCEPROP 1 LASTPIN (850 7025) $PN 1
J 0
(860 7005);
DISPLAY 0.787234 (860 7005);
FORCEPROP 1 LASTPIN (850 6825) $PN 2
J 0
(860 6805);
DISPLAY 0.787234 (860 6805);
FORCEPROP 2 LAST CDS_LIB pure_quanta
J 0
(850 6925);
PAINT MONO (850 6925);
DISPLAY INVISIBLE (850 6925);
FORCEPROP 1 LAST $LOCATION C303
J 0
(900 7125);
DISPLAY 1.021277 (900 7125);
DISPLAY INVISIBLE (900 7125);
FORCEPROP 2 LAST CDS_LOCATION C303
J 0
(900 7125);
DISPLAY 1.021277 (900 7125);
DISPLAY INVISIBLE (900 7125);
FORCEPROP 2 LAST $SEC 1
J 0
(900 7125);
DISPLAY 0.680851 (900 7125);
PAINT MONO (900 7125);
DISPLAY INVISIBLE (900 7125);
FORCEPROP 2 LAST CDS_SEC 1
J 0
(900 7125);
DISPLAY 1.021277 (900 7125);
DISPLAY INVISIBLE (900 7125);
FORCEPROP 1 LAST PATH I139
J 0
(900 7075);
DISPLAY 0.978723 (900 7075);
PAINT WHITE (900 7075);
DISPLAY INVISIBLE (900 7075);
FORCEADD Q_CAP..1
(-6800 4625);
FORCEPROP 1 LAST PART_NUMBER CH6101MEB03
J 0
(-6750 4475);
DISPLAY 0.638298 (-6750 4475);
DISPLAY INVISIBLE (-6750 4475);
FORCEPROP 1 LAST VOLTAGE 6.3V
J 0
(-6750 4625);
DISPLAY 0.638298 (-6750 4625);
FORCEPROP 1 LAST VALUE 10UF
J 0
(-6750 4675);
DISPLAY 0.638298 (-6750 4675);
FORCEPROP 1 LAST TOLERANCE 20%
J 0
(-6750 4575);
DISPLAY 0.638298 (-6750 4575);
FORCEPROP 1 LAST MATERIAL X6S
J 0
(-6750 4525);
DISPLAY 0.638298 (-6750 4525);
FORCEPROP 1 LAST PACK_TYPE C0402
J 0
(-6750 4425);
DISPLAY 0.638298 (-6750 4425);
FORCEPROP 1 LAST $LOCATION C229
J 0
(-6750 4725);
DISPLAY 0.638298 (-6750 4725);
FORCEPROP 1 LASTPIN (-6800 4725) $PN 1
J 0
(-6790 4705);
DISPLAY 0.787234 (-6790 4705);
FORCEPROP 1 LASTPIN (-6800 4525) $PN 2
J 0
(-6790 4505);
DISPLAY 0.787234 (-6790 4505);
FORCEPROP 2 LAST CDS_LIB pure_quanta
J 0
(-6800 4625);
PAINT MONO (-6800 4625);
DISPLAY INVISIBLE (-6800 4625);
FORCEPROP 1 LAST $LOCATION C229
J 0
(-6750 4825);
DISPLAY 1.021277 (-6750 4825);
DISPLAY INVISIBLE (-6750 4825);
FORCEPROP 2 LAST CDS_LOCATION C229
J 0
(-6750 4825);
DISPLAY 1.021277 (-6750 4825);
DISPLAY INVISIBLE (-6750 4825);
FORCEPROP 2 LAST $SEC 1
J 0
(-6750 4825);
DISPLAY 0.680851 (-6750 4825);
PAINT MONO (-6750 4825);
DISPLAY INVISIBLE (-6750 4825);
FORCEPROP 2 LAST CDS_SEC 1
J 0
(-6750 4825);
DISPLAY 1.021277 (-6750 4825);
DISPLAY INVISIBLE (-6750 4825);
FORCEPROP 1 LAST PATH I14
J 0
(-6750 4775);
DISPLAY 0.978723 (-6750 4775);
PAINT WHITE (-6750 4775);
DISPLAY INVISIBLE (-6750 4775);
FORCEADD Q_CAP..1
(1300 6150);
FORCEPROP 1 LAST PART_NUMBER CH622KMEB01
J 0
(1350 6000);
DISPLAY 0.638298 (1350 6000);
DISPLAY INVISIBLE (1350 6000);
FORCEPROP 1 LAST TOLERANCE 20%
J 0
(1350 6100);
DISPLAY 0.638298 (1350 6100);
FORCEPROP 1 LAST VOLTAGE 4V
J 0
(1350 6150);
DISPLAY 0.638298 (1350 6150);
FORCEPROP 1 LAST VALUE 22UF
J 0
(1350 6200);
DISPLAY 0.638298 (1350 6200);
FORCEPROP 1 LAST PACK_TYPE C0402
J 0
(1350 5950);
DISPLAY 0.638298 (1350 5950);
FORCEPROP 1 LAST MATERIAL X6S
J 0
(1350 6050);
DISPLAY 0.638298 (1350 6050);
FORCEPROP 1 LAST $LOCATION C308
J 0
(1350 6250);
DISPLAY 0.638298 (1350 6250);
FORCEPROP 1 LASTPIN (1300 6250) $PN 1
J 0
(1310 6230);
DISPLAY 0.787234 (1310 6230);
FORCEPROP 1 LASTPIN (1300 6050) $PN 2
J 0
(1310 6030);
DISPLAY 0.787234 (1310 6030);
FORCEPROP 2 LAST CDS_LIB pure_quanta
J 0
(1300 6150);
PAINT MONO (1300 6150);
DISPLAY INVISIBLE (1300 6150);
FORCEPROP 1 LAST $LOCATION C308
J 0
(1350 6350);
DISPLAY 1.021277 (1350 6350);
DISPLAY INVISIBLE (1350 6350);
FORCEPROP 2 LAST CDS_LOCATION C308
J 0
(1350 6350);
DISPLAY 1.021277 (1350 6350);
DISPLAY INVISIBLE (1350 6350);
FORCEPROP 2 LAST $SEC 1
J 0
(1350 6350);
DISPLAY 0.680851 (1350 6350);
PAINT MONO (1350 6350);
DISPLAY INVISIBLE (1350 6350);
FORCEPROP 2 LAST CDS_SEC 1
J 0
(1350 6350);
DISPLAY 1.021277 (1350 6350);
DISPLAY INVISIBLE (1350 6350);
FORCEPROP 1 LAST PATH I140
J 0
(1350 6300);
DISPLAY 0.978723 (1350 6300);
PAINT WHITE (1350 6300);
DISPLAY INVISIBLE (1350 6300);
FORCEADD UNIVERSAL_GND..1
(1300 6575);
FORCEPROP 3 LASTPIN (1300 6625) SIG_NAME GND\g
J 0
(1310 6635);
DISPLAY 0.659574 (1310 6635);
PAINT MONO (1310 6635);
DISPLAY INVISIBLE (1310 6635);
FORCEPROP 2 LAST CDS_LIB logical_power
J 0
(1300 6575);
PAINT MONO (1300 6575);
DISPLAY INVISIBLE (1300 6575);
FORCEPROP 1 LAST HDL_POWER GND
J 1
(1325 6500);
DISPLAY 0.872340 (1325 6500);
PAINT GREEN (1325 6500);
DISPLAY INVISIBLE (1325 6500);
FORCEPROP 1 LAST PATH I141
J 0
(1375 6575);
DISPLAY 0.872340 (1375 6575);
PAINT AQUA (1375 6575);
DISPLAY INVISIBLE (1375 6575);
FORCEADD Q_CAP..1
(1300 6925);
FORCEPROP 1 LAST PART_NUMBER CH622KMEB01
J 0
(1350 6775);
DISPLAY 0.638298 (1350 6775);
DISPLAY INVISIBLE (1350 6775);
FORCEPROP 1 LAST VOLTAGE 4V
J 0
(1350 6925);
DISPLAY 0.638298 (1350 6925);
FORCEPROP 1 LAST TOLERANCE 20%
J 0
(1350 6875);
DISPLAY 0.638298 (1350 6875);
FORCEPROP 1 LAST PACK_TYPE C0402
J 0
(1350 6725);
DISPLAY 0.638298 (1350 6725);
FORCEPROP 1 LAST MATERIAL X6S
J 0
(1350 6825);
DISPLAY 0.638298 (1350 6825);
FORCEPROP 1 LAST VALUE 22UF
J 0
(1350 6975);
DISPLAY 0.638298 (1350 6975);
FORCEPROP 1 LAST $LOCATION C307
J 0
(1350 7025);
DISPLAY 0.638298 (1350 7025);
FORCEPROP 1 LASTPIN (1300 7025) $PN 1
J 0
(1310 7005);
DISPLAY 0.787234 (1310 7005);
FORCEPROP 1 LASTPIN (1300 6825) $PN 2
J 0
(1310 6805);
DISPLAY 0.787234 (1310 6805);
FORCEPROP 2 LAST CDS_LIB pure_quanta
J 0
(1300 6925);
PAINT MONO (1300 6925);
DISPLAY INVISIBLE (1300 6925);
FORCEPROP 1 LAST $LOCATION C307
J 0
(1350 7125);
DISPLAY 1.021277 (1350 7125);
DISPLAY INVISIBLE (1350 7125);
FORCEPROP 2 LAST CDS_LOCATION C307
J 0
(1350 7125);
DISPLAY 1.021277 (1350 7125);
DISPLAY INVISIBLE (1350 7125);
FORCEPROP 2 LAST $SEC 1
J 0
(1350 7125);
DISPLAY 0.680851 (1350 7125);
PAINT MONO (1350 7125);
DISPLAY INVISIBLE (1350 7125);
FORCEPROP 2 LAST CDS_SEC 1
J 0
(1350 7125);
DISPLAY 1.021277 (1350 7125);
DISPLAY INVISIBLE (1350 7125);
FORCEPROP 1 LAST PATH I142
J 0
(1350 7075);
DISPLAY 0.978723 (1350 7075);
PAINT WHITE (1350 7075);
DISPLAY INVISIBLE (1350 7075);
FORCEADD Q_CAP..1
(-6350 3050);
FORCEPROP 1 LAST PART_NUMBER CH622KMEB01
J 0
(-6300 2900);
DISPLAY 0.638298 (-6300 2900);
DISPLAY INVISIBLE (-6300 2900);
FORCEPROP 1 LAST VOLTAGE 4V
J 0
(-6300 3050);
DISPLAY 0.638298 (-6300 3050);
FORCEPROP 1 LAST TOLERANCE 20%
J 0
(-6300 3000);
DISPLAY 0.638298 (-6300 3000);
FORCEPROP 1 LAST VALUE 22UF
J 0
(-6300 3100);
DISPLAY 0.638298 (-6300 3100);
FORCEPROP 1 LAST PACK_TYPE C0402
J 0
(-6300 2850);
DISPLAY 0.638298 (-6300 2850);
FORCEPROP 1 LAST MATERIAL X6S
J 0
(-6300 2950);
DISPLAY 0.638298 (-6300 2950);
FORCEPROP 1 LAST $LOCATION C427
J 0
(-6300 3150);
DISPLAY 0.978723 (-6300 3150);
FORCEPROP 1 LASTPIN (-6350 3150) $PN 1
J 0
(-6340 3130);
DISPLAY 0.787234 (-6340 3130);
FORCEPROP 1 LASTPIN (-6350 2950) $PN 2
J 0
(-6340 2930);
DISPLAY 0.787234 (-6340 2930);
FORCEPROP 2 LAST CDS_LIB pure_quanta
J 0
(-6350 3050);
PAINT MONO (-6350 3050);
DISPLAY INVISIBLE (-6350 3050);
FORCEPROP 2 LAST CDS_LOCATION C427
J 0
(-6300 3250);
DISPLAY 1.021277 (-6300 3250);
DISPLAY INVISIBLE (-6300 3250);
FORCEPROP 2 LAST $SEC 1
J 0
(-6300 3250);
DISPLAY 0.680851 (-6300 3250);
PAINT MONO (-6300 3250);
DISPLAY INVISIBLE (-6300 3250);
FORCEPROP 2 LAST CDS_SEC 1
J 0
(-6300 3250);
DISPLAY 1.021277 (-6300 3250);
DISPLAY INVISIBLE (-6300 3250);
FORCEPROP 1 LAST PATH I15
J 0
(-6300 3200);
DISPLAY 0.978723 (-6300 3200);
PAINT WHITE (-6300 3200);
DISPLAY INVISIBLE (-6300 3200);
FORCEADD Q_CAP..1
(-6350 3850);
FORCEPROP 1 LAST PART_NUMBER CH647KMEA04
J 0
(-6300 3700);
DISPLAY 0.638298 (-6300 3700);
DISPLAY INVISIBLE (-6300 3700);
FORCEPROP 1 LAST VOLTAGE 4V
J 0
(-6300 3850);
DISPLAY 0.638298 (-6300 3850);
FORCEPROP 1 LAST TOLERANCE 20%
J 0
(-6300 3800);
DISPLAY 0.638298 (-6300 3800);
FORCEPROP 1 LAST PACK_TYPE C0805
J 0
(-6300 3650);
DISPLAY 0.638298 (-6300 3650);
FORCEPROP 1 LAST VALUE 47UF
J 0
(-6300 3900);
DISPLAY 0.638298 (-6300 3900);
FORCEPROP 1 LAST MATERIAL X6S
J 0
(-6300 3750);
DISPLAY 0.638298 (-6300 3750);
FORCEPROP 1 LAST $LOCATION C235
J 0
(-6300 3950);
DISPLAY 0.638298 (-6300 3950);
FORCEPROP 1 LASTPIN (-6350 3950) $PN 1
J 0
(-6340 3930);
DISPLAY 0.787234 (-6340 3930);
FORCEPROP 1 LASTPIN (-6350 3750) $PN 2
J 0
(-6340 3730);
DISPLAY 0.787234 (-6340 3730);
FORCEPROP 2 LAST CDS_LIB pure_quanta
J 0
(-6350 3850);
PAINT MONO (-6350 3850);
DISPLAY INVISIBLE (-6350 3850);
FORCEPROP 1 LAST $LOCATION C235
J 0
(-6300 4050);
DISPLAY 1.021277 (-6300 4050);
DISPLAY INVISIBLE (-6300 4050);
FORCEPROP 2 LAST CDS_LOCATION C235
J 0
(-6300 4050);
DISPLAY 1.021277 (-6300 4050);
DISPLAY INVISIBLE (-6300 4050);
FORCEPROP 2 LAST $SEC 1
J 0
(-6300 4050);
DISPLAY 0.680851 (-6300 4050);
PAINT MONO (-6300 4050);
DISPLAY INVISIBLE (-6300 4050);
FORCEPROP 2 LAST CDS_SEC 1
J 0
(-6300 4050);
DISPLAY 1.021277 (-6300 4050);
DISPLAY INVISIBLE (-6300 4050);
FORCEPROP 1 LAST PATH I16
J 0
(-6300 4000);
DISPLAY 0.978723 (-6300 4000);
PAINT WHITE (-6300 4000);
DISPLAY INVISIBLE (-6300 4000);
FORCEADD Q_CAP..1
(-5900 3050);
FORCEPROP 1 LAST PART_NUMBER CH622KMEB01
J 0
(-5850 2900);
DISPLAY 0.638298 (-5850 2900);
DISPLAY INVISIBLE (-5850 2900);
FORCEPROP 1 LAST VOLTAGE 4V
J 0
(-5850 3050);
DISPLAY 0.638298 (-5850 3050);
FORCEPROP 1 LAST TOLERANCE 20%
J 0
(-5850 3000);
DISPLAY 0.638298 (-5850 3000);
FORCEPROP 1 LAST PACK_TYPE C0402
J 0
(-5850 2850);
DISPLAY 0.638298 (-5850 2850);
FORCEPROP 1 LAST VALUE 22UF
J 0
(-5850 3100);
DISPLAY 0.638298 (-5850 3100);
FORCEPROP 1 LAST MATERIAL X6S
J 0
(-5850 2950);
DISPLAY 0.638298 (-5850 2950);
FORCEPROP 1 LAST $LOCATION C429
J 0
(-5850 3150);
DISPLAY 0.978723 (-5850 3150);
FORCEPROP 1 LASTPIN (-5900 3150) $PN 1
J 0
(-5890 3130);
DISPLAY 0.787234 (-5890 3130);
FORCEPROP 1 LASTPIN (-5900 2950) $PN 2
J 0
(-5890 2930);
DISPLAY 0.787234 (-5890 2930);
FORCEPROP 2 LAST CDS_LIB pure_quanta
J 0
(-5900 3050);
PAINT MONO (-5900 3050);
DISPLAY INVISIBLE (-5900 3050);
FORCEPROP 2 LAST CDS_LOCATION C429
J 0
(-5850 3250);
DISPLAY 1.021277 (-5850 3250);
DISPLAY INVISIBLE (-5850 3250);
FORCEPROP 2 LAST $SEC 1
J 0
(-5850 3250);
DISPLAY 0.680851 (-5850 3250);
PAINT MONO (-5850 3250);
DISPLAY INVISIBLE (-5850 3250);
FORCEPROP 2 LAST CDS_SEC 1
J 0
(-5850 3250);
DISPLAY 1.021277 (-5850 3250);
DISPLAY INVISIBLE (-5850 3250);
FORCEPROP 1 LAST PATH I17
J 0
(-5850 3200);
DISPLAY 0.978723 (-5850 3200);
PAINT WHITE (-5850 3200);
DISPLAY INVISIBLE (-5850 3200);
FORCEADD Q_CAP..1
(-5900 3850);
FORCEPROP 1 LAST PART_NUMBER CH647KMEA04
J 0
(-5850 3700);
DISPLAY 0.638298 (-5850 3700);
DISPLAY INVISIBLE (-5850 3700);
FORCEPROP 1 LAST VOLTAGE 4V
J 0
(-5850 3850);
DISPLAY 0.638298 (-5850 3850);
FORCEPROP 1 LAST TOLERANCE 20%
J 0
(-5850 3800);
DISPLAY 0.638298 (-5850 3800);
FORCEPROP 1 LAST PACK_TYPE C0805
J 0
(-5850 3650);
DISPLAY 0.638298 (-5850 3650);
FORCEPROP 1 LAST MATERIAL X6S
J 0
(-5850 3750);
DISPLAY 0.638298 (-5850 3750);
FORCEPROP 1 LAST VALUE 47UF
J 0
(-5850 3900);
DISPLAY 0.638298 (-5850 3900);
FORCEPROP 1 LAST $LOCATION C240
J 0
(-5850 3950);
DISPLAY 0.638298 (-5850 3950);
FORCEPROP 1 LASTPIN (-5900 3950) $PN 1
J 0
(-5890 3930);
DISPLAY 0.787234 (-5890 3930);
FORCEPROP 1 LASTPIN (-5900 3750) $PN 2
J 0
(-5890 3730);
DISPLAY 0.787234 (-5890 3730);
FORCEPROP 2 LAST CDS_LIB pure_quanta
J 0
(-5900 3850);
PAINT MONO (-5900 3850);
DISPLAY INVISIBLE (-5900 3850);
FORCEPROP 1 LAST $LOCATION C240
J 0
(-5850 4050);
DISPLAY 1.021277 (-5850 4050);
DISPLAY INVISIBLE (-5850 4050);
FORCEPROP 2 LAST CDS_LOCATION C240
J 0
(-5850 4050);
DISPLAY 1.021277 (-5850 4050);
DISPLAY INVISIBLE (-5850 4050);
FORCEPROP 2 LAST $SEC 1
J 0
(-5850 4050);
DISPLAY 0.680851 (-5850 4050);
PAINT MONO (-5850 4050);
DISPLAY INVISIBLE (-5850 4050);
FORCEPROP 2 LAST CDS_SEC 1
J 0
(-5850 4050);
DISPLAY 1.021277 (-5850 4050);
DISPLAY INVISIBLE (-5850 4050);
FORCEPROP 1 LAST PATH I18
J 0
(-5850 4000);
DISPLAY 0.978723 (-5850 4000);
PAINT WHITE (-5850 4000);
DISPLAY INVISIBLE (-5850 4000);
FORCEADD Q_CAP..1
(-6350 4625);
FORCEPROP 1 LAST PART_NUMBER CH6101MEB03
J 0
(-6300 4475);
DISPLAY 0.638298 (-6300 4475);
DISPLAY INVISIBLE (-6300 4475);
FORCEPROP 1 LAST VOLTAGE 6.3V
J 0
(-6300 4625);
DISPLAY 0.638298 (-6300 4625);
FORCEPROP 1 LAST VALUE 10UF
J 0
(-6300 4675);
DISPLAY 0.638298 (-6300 4675);
FORCEPROP 1 LAST TOLERANCE 20%
J 0
(-6300 4575);
DISPLAY 0.638298 (-6300 4575);
FORCEPROP 1 LAST MATERIAL X6S
J 0
(-6300 4525);
DISPLAY 0.638298 (-6300 4525);
FORCEPROP 1 LAST PACK_TYPE C0402
J 0
(-6300 4425);
DISPLAY 0.638298 (-6300 4425);
FORCEPROP 1 LAST $LOCATION C234
J 0
(-6300 4725);
DISPLAY 0.638298 (-6300 4725);
FORCEPROP 1 LASTPIN (-6350 4725) $PN 1
J 0
(-6340 4705);
DISPLAY 0.787234 (-6340 4705);
FORCEPROP 1 LASTPIN (-6350 4525) $PN 2
J 0
(-6340 4505);
DISPLAY 0.787234 (-6340 4505);
FORCEPROP 2 LAST CDS_LIB pure_quanta
J 0
(-6350 4625);
PAINT MONO (-6350 4625);
DISPLAY INVISIBLE (-6350 4625);
FORCEPROP 1 LAST $LOCATION C234
J 0
(-6300 4825);
DISPLAY 1.021277 (-6300 4825);
DISPLAY INVISIBLE (-6300 4825);
FORCEPROP 2 LAST CDS_LOCATION C234
J 0
(-6300 4825);
DISPLAY 1.021277 (-6300 4825);
DISPLAY INVISIBLE (-6300 4825);
FORCEPROP 2 LAST $SEC 1
J 0
(-6300 4825);
DISPLAY 0.680851 (-6300 4825);
PAINT MONO (-6300 4825);
DISPLAY INVISIBLE (-6300 4825);
FORCEPROP 2 LAST CDS_SEC 1
J 0
(-6300 4825);
DISPLAY 1.021277 (-6300 4825);
DISPLAY INVISIBLE (-6300 4825);
FORCEPROP 1 LAST PATH I19
J 0
(-6300 4775);
DISPLAY 0.978723 (-6300 4775);
PAINT WHITE (-6300 4775);
DISPLAY INVISIBLE (-6300 4775);
FORCEADD Q_CAP..1
(-6800 2225);
FORCEPROP 1 LAST PART_NUMBER CH622KMEB01
J 0
(-6750 2075);
DISPLAY 0.638298 (-6750 2075);
DISPLAY INVISIBLE (-6750 2075);
FORCEPROP 1 LAST VOLTAGE 4V
J 0
(-6750 2225);
DISPLAY 0.638298 (-6750 2225);
FORCEPROP 1 LAST TOLERANCE 20%
J 0
(-6750 2175);
DISPLAY 0.638298 (-6750 2175);
FORCEPROP 1 LAST VALUE 22UF
J 0
(-6750 2275);
DISPLAY 0.638298 (-6750 2275);
FORCEPROP 1 LAST PACK_TYPE C0402
J 0
(-6750 2025);
DISPLAY 0.638298 (-6750 2025);
FORCEPROP 1 LAST MATERIAL X6S
J 0
(-6750 2125);
DISPLAY 0.638298 (-6750 2125);
FORCEPROP 1 LAST $LOCATION C426
J 0
(-6750 2325);
DISPLAY 0.978723 (-6750 2325);
FORCEPROP 1 LASTPIN (-6800 2325) $PN 1
J 0
(-6790 2305);
DISPLAY 0.787234 (-6790 2305);
FORCEPROP 1 LASTPIN (-6800 2125) $PN 2
J 0
(-6790 2105);
DISPLAY 0.787234 (-6790 2105);
FORCEPROP 2 LAST CDS_LIB pure_quanta
J 0
(-6800 2225);
PAINT MONO (-6800 2225);
DISPLAY INVISIBLE (-6800 2225);
FORCEPROP 2 LAST CDS_LOCATION C426
J 0
(-6750 2425);
DISPLAY 1.021277 (-6750 2425);
DISPLAY INVISIBLE (-6750 2425);
FORCEPROP 2 LAST $SEC 1
J 0
(-6750 2425);
DISPLAY 0.680851 (-6750 2425);
PAINT MONO (-6750 2425);
DISPLAY INVISIBLE (-6750 2425);
FORCEPROP 2 LAST CDS_SEC 1
J 0
(-6750 2425);
DISPLAY 1.021277 (-6750 2425);
DISPLAY INVISIBLE (-6750 2425);
FORCEPROP 1 LAST PATH I2
J 0
(-6750 2375);
DISPLAY 0.978723 (-6750 2375);
PAINT WHITE (-6750 2375);
DISPLAY INVISIBLE (-6750 2375);
FORCEADD Q_CAP..1
(-5900 4625);
FORCEPROP 1 LAST PART_NUMBER CH6101MEB03
J 0
(-5850 4475);
DISPLAY 0.638298 (-5850 4475);
DISPLAY INVISIBLE (-5850 4475);
FORCEPROP 1 LAST VALUE 10UF
J 0
(-5850 4675);
DISPLAY 0.638298 (-5850 4675);
FORCEPROP 1 LAST VOLTAGE 6.3V
J 0
(-5850 4625);
DISPLAY 0.638298 (-5850 4625);
FORCEPROP 1 LAST PACK_TYPE C0402
J 0
(-5850 4425);
DISPLAY 0.638298 (-5850 4425);
FORCEPROP 1 LAST MATERIAL X6S
J 0
(-5850 4525);
DISPLAY 0.638298 (-5850 4525);
FORCEPROP 1 LAST TOLERANCE 20%
J 0
(-5850 4575);
DISPLAY 0.638298 (-5850 4575);
FORCEPROP 1 LAST $LOCATION C239
J 0
(-5850 4725);
DISPLAY 0.638298 (-5850 4725);
FORCEPROP 1 LASTPIN (-5900 4725) $PN 1
J 0
(-5890 4705);
DISPLAY 0.787234 (-5890 4705);
FORCEPROP 1 LASTPIN (-5900 4525) $PN 2
J 0
(-5890 4505);
DISPLAY 0.787234 (-5890 4505);
FORCEPROP 2 LAST CDS_LIB pure_quanta
J 0
(-5900 4625);
PAINT MONO (-5900 4625);
DISPLAY INVISIBLE (-5900 4625);
FORCEPROP 1 LAST $LOCATION C239
J 0
(-5850 4825);
DISPLAY 1.021277 (-5850 4825);
DISPLAY INVISIBLE (-5850 4825);
FORCEPROP 2 LAST CDS_LOCATION C239
J 0
(-5850 4825);
DISPLAY 1.021277 (-5850 4825);
DISPLAY INVISIBLE (-5850 4825);
FORCEPROP 2 LAST $SEC 1
J 0
(-5850 4825);
DISPLAY 0.680851 (-5850 4825);
PAINT MONO (-5850 4825);
DISPLAY INVISIBLE (-5850 4825);
FORCEPROP 2 LAST CDS_SEC 1
J 0
(-5850 4825);
DISPLAY 1.021277 (-5850 4825);
DISPLAY INVISIBLE (-5850 4825);
FORCEPROP 1 LAST PATH I20
J 0
(-5850 4775);
DISPLAY 0.978723 (-5850 4775);
PAINT WHITE (-5850 4775);
DISPLAY INVISIBLE (-5850 4775);
FORCEADD UNIVERSAL_POWER..1
(-7250 4900);
FORCEPROP 3 LASTPIN (-7250 4850) SIG_NAME PVCCIN_CPU1\g
J 0
(-7240 4860);
DISPLAY 0.659574 (-7240 4860);
PAINT MONO (-7240 4860);
DISPLAY INVISIBLE (-7240 4860);
FORCEPROP 1 LAST HDL_POWER PVCCIN_CPU1
J 1
(-7050 4950);
DISPLAY 0.872340 (-7050 4950);
PAINT GREEN (-7050 4950);
FORCEPROP 2 LAST CDS_LIB logical_power
J 0
(-7250 4900);
DISPLAY INVISIBLE (-7250 4900);
FORCEPROP 1 LAST PATH I21
J 0
(-7200 4925);
DISPLAY 0.872340 (-7200 4925);
PAINT AQUA (-7200 4925);
DISPLAY INVISIBLE (-7200 4925);
FORCEADD Q_CAP..1
(-7250 5400);
FORCEPROP 1 LAST PART_NUMBER CH6101MEB03
J 0
(-7200 5250);
DISPLAY 0.638298 (-7200 5250);
DISPLAY INVISIBLE (-7200 5250);
FORCEPROP 1 LAST VOLTAGE 6.3V
J 0
(-7200 5400);
DISPLAY 0.638298 (-7200 5400);
FORCEPROP 1 LAST TOLERANCE 20%
J 0
(-7200 5350);
DISPLAY 0.638298 (-7200 5350);
FORCEPROP 1 LAST PACK_TYPE C0402
J 0
(-7200 5200);
DISPLAY 0.638298 (-7200 5200);
FORCEPROP 1 LAST MATERIAL X6S
J 0
(-7200 5300);
DISPLAY 0.638298 (-7200 5300);
FORCEPROP 1 LAST VALUE 10UF
J 0
(-7200 5450);
DISPLAY 0.638298 (-7200 5450);
FORCEPROP 1 LAST $LOCATION C223
J 0
(-7200 5500);
DISPLAY 0.638298 (-7200 5500);
FORCEPROP 1 LASTPIN (-7250 5500) $PN 1
J 0
(-7240 5480);
DISPLAY 0.787234 (-7240 5480);
FORCEPROP 1 LASTPIN (-7250 5300) $PN 2
J 0
(-7240 5280);
DISPLAY 0.787234 (-7240 5280);
FORCEPROP 2 LAST CDS_LIB pure_quanta
J 0
(-7250 5400);
PAINT MONO (-7250 5400);
DISPLAY INVISIBLE (-7250 5400);
FORCEPROP 1 LAST $LOCATION C223
J 0
(-7200 5600);
DISPLAY 1.021277 (-7200 5600);
DISPLAY INVISIBLE (-7200 5600);
FORCEPROP 2 LAST CDS_LOCATION C223
J 0
(-7200 5600);
DISPLAY 1.021277 (-7200 5600);
DISPLAY INVISIBLE (-7200 5600);
FORCEPROP 2 LAST $SEC 1
J 0
(-7200 5600);
DISPLAY 0.680851 (-7200 5600);
PAINT MONO (-7200 5600);
DISPLAY INVISIBLE (-7200 5600);
FORCEPROP 2 LAST CDS_SEC 1
J 0
(-7200 5600);
DISPLAY 1.021277 (-7200 5600);
DISPLAY INVISIBLE (-7200 5600);
FORCEPROP 1 LAST PATH I22
J 0
(-7200 5550);
DISPLAY 0.978723 (-7200 5550);
PAINT WHITE (-7200 5550);
DISPLAY INVISIBLE (-7200 5550);
FORCEADD Q_CAP..1
(-6800 5400);
FORCEPROP 1 LAST PART_NUMBER CH6101MEB03
J 0
(-6750 5250);
DISPLAY 0.638298 (-6750 5250);
DISPLAY INVISIBLE (-6750 5250);
FORCEPROP 1 LAST TOLERANCE 20%
J 0
(-6750 5350);
DISPLAY 0.638298 (-6750 5350);
FORCEPROP 1 LAST VALUE 10UF
J 0
(-6750 5450);
DISPLAY 0.638298 (-6750 5450);
FORCEPROP 1 LAST PACK_TYPE C0402
J 0
(-6750 5200);
DISPLAY 0.638298 (-6750 5200);
FORCEPROP 1 LAST MATERIAL X6S
J 0
(-6750 5300);
DISPLAY 0.638298 (-6750 5300);
FORCEPROP 1 LAST VOLTAGE 6.3V
J 0
(-6750 5400);
DISPLAY 0.638298 (-6750 5400);
FORCEPROP 1 LAST $LOCATION C228
J 0
(-6750 5500);
DISPLAY 0.638298 (-6750 5500);
FORCEPROP 1 LASTPIN (-6800 5500) $PN 1
J 0
(-6790 5480);
DISPLAY 0.787234 (-6790 5480);
FORCEPROP 1 LASTPIN (-6800 5300) $PN 2
J 0
(-6790 5280);
DISPLAY 0.787234 (-6790 5280);
FORCEPROP 2 LAST CDS_LIB pure_quanta
J 0
(-6800 5400);
PAINT MONO (-6800 5400);
DISPLAY INVISIBLE (-6800 5400);
FORCEPROP 1 LAST $LOCATION C228
J 0
(-6750 5600);
DISPLAY 1.021277 (-6750 5600);
DISPLAY INVISIBLE (-6750 5600);
FORCEPROP 2 LAST CDS_LOCATION C228
J 0
(-6750 5600);
DISPLAY 1.021277 (-6750 5600);
DISPLAY INVISIBLE (-6750 5600);
FORCEPROP 2 LAST $SEC 1
J 0
(-6750 5600);
DISPLAY 0.680851 (-6750 5600);
PAINT MONO (-6750 5600);
DISPLAY INVISIBLE (-6750 5600);
FORCEPROP 2 LAST CDS_SEC 1
J 0
(-6750 5600);
DISPLAY 1.021277 (-6750 5600);
DISPLAY INVISIBLE (-6750 5600);
FORCEPROP 1 LAST PATH I23
J 0
(-6750 5550);
DISPLAY 0.978723 (-6750 5550);
PAINT WHITE (-6750 5550);
DISPLAY INVISIBLE (-6750 5550);
FORCEADD UNIVERSAL_POWER..1
(-7250 5675);
FORCEPROP 3 LASTPIN (-7250 5625) SIG_NAME PVCCIN_CPU1\g
J 0
(-7240 5635);
DISPLAY 0.659574 (-7240 5635);
PAINT MONO (-7240 5635);
DISPLAY INVISIBLE (-7240 5635);
FORCEPROP 1 LAST HDL_POWER PVCCIN_CPU1
J 1
(-7050 5725);
DISPLAY 0.872340 (-7050 5725);
PAINT GREEN (-7050 5725);
FORCEPROP 2 LAST CDS_LIB logical_power
J 0
(-7250 5675);
DISPLAY INVISIBLE (-7250 5675);
FORCEPROP 1 LAST PATH I24
J 0
(-7200 5700);
DISPLAY 0.872340 (-7200 5700);
PAINT AQUA (-7200 5700);
DISPLAY INVISIBLE (-7200 5700);
FORCEADD Q_CAP..1
(-7275 6150);
FORCEPROP 1 LAST PART_NUMBER CH6101MEB03
J 0
(-7225 6000);
DISPLAY 0.638298 (-7225 6000);
DISPLAY INVISIBLE (-7225 6000);
FORCEPROP 1 LAST VOLTAGE 6.3V
J 0
(-7225 6150);
DISPLAY 0.638298 (-7225 6150);
FORCEPROP 1 LAST VALUE 10UF
J 0
(-7225 6200);
DISPLAY 0.638298 (-7225 6200);
FORCEPROP 1 LAST TOLERANCE 20%
J 0
(-7225 6100);
DISPLAY 0.638298 (-7225 6100);
FORCEPROP 1 LAST PACK_TYPE C0402
J 0
(-7225 5950);
DISPLAY 0.638298 (-7225 5950);
FORCEPROP 1 LAST MATERIAL X6S
J 0
(-7225 6050);
DISPLAY 0.638298 (-7225 6050);
FORCEPROP 1 LAST $LOCATION C222
J 0
(-7225 6250);
DISPLAY 0.638298 (-7225 6250);
FORCEPROP 1 LASTPIN (-7275 6250) $PN 1
J 0
(-7265 6230);
DISPLAY 0.787234 (-7265 6230);
FORCEPROP 1 LASTPIN (-7275 6050) $PN 2
J 0
(-7265 6030);
DISPLAY 0.787234 (-7265 6030);
FORCEPROP 2 LAST CDS_LIB pure_quanta
J 0
(-7275 6150);
PAINT MONO (-7275 6150);
DISPLAY INVISIBLE (-7275 6150);
FORCEPROP 1 LAST $LOCATION C222
J 0
(-7225 6350);
DISPLAY 1.021277 (-7225 6350);
DISPLAY INVISIBLE (-7225 6350);
FORCEPROP 2 LAST CDS_LOCATION C222
J 0
(-7225 6350);
DISPLAY 1.021277 (-7225 6350);
DISPLAY INVISIBLE (-7225 6350);
FORCEPROP 2 LAST $SEC 1
J 0
(-7225 6350);
DISPLAY 0.680851 (-7225 6350);
PAINT MONO (-7225 6350);
DISPLAY INVISIBLE (-7225 6350);
FORCEPROP 2 LAST CDS_SEC 1
J 0
(-7225 6350);
DISPLAY 1.021277 (-7225 6350);
DISPLAY INVISIBLE (-7225 6350);
FORCEPROP 1 LAST PATH I25
J 0
(-7225 6300);
DISPLAY 0.978723 (-7225 6300);
PAINT WHITE (-7225 6300);
DISPLAY INVISIBLE (-7225 6300);
FORCEADD Q_CAP..1
(-6825 6150);
FORCEPROP 1 LAST PART_NUMBER CH6101MEB03
J 0
(-6775 6000);
DISPLAY 0.638298 (-6775 6000);
DISPLAY INVISIBLE (-6775 6000);
FORCEPROP 1 LAST VOLTAGE 6.3V
J 0
(-6775 6150);
DISPLAY 0.638298 (-6775 6150);
FORCEPROP 1 LAST VALUE 10UF
J 0
(-6775 6200);
DISPLAY 0.638298 (-6775 6200);
FORCEPROP 1 LAST TOLERANCE 20%
J 0
(-6775 6100);
DISPLAY 0.638298 (-6775 6100);
FORCEPROP 1 LAST PACK_TYPE C0402
J 0
(-6775 5950);
DISPLAY 0.638298 (-6775 5950);
FORCEPROP 1 LAST MATERIAL X6S
J 0
(-6775 6050);
DISPLAY 0.638298 (-6775 6050);
FORCEPROP 1 LAST $LOCATION C227
J 0
(-6775 6250);
DISPLAY 0.638298 (-6775 6250);
FORCEPROP 1 LASTPIN (-6825 6250) $PN 1
J 0
(-6815 6230);
DISPLAY 0.787234 (-6815 6230);
FORCEPROP 1 LASTPIN (-6825 6050) $PN 2
J 0
(-6815 6030);
DISPLAY 0.787234 (-6815 6030);
FORCEPROP 2 LAST CDS_LIB pure_quanta
J 0
(-6825 6150);
PAINT MONO (-6825 6150);
DISPLAY INVISIBLE (-6825 6150);
FORCEPROP 1 LAST $LOCATION C227
J 0
(-6775 6350);
DISPLAY 1.021277 (-6775 6350);
DISPLAY INVISIBLE (-6775 6350);
FORCEPROP 2 LAST CDS_LOCATION C227
J 0
(-6775 6350);
DISPLAY 1.021277 (-6775 6350);
DISPLAY INVISIBLE (-6775 6350);
FORCEPROP 2 LAST $SEC 1
J 0
(-6775 6350);
DISPLAY 0.680851 (-6775 6350);
PAINT MONO (-6775 6350);
DISPLAY INVISIBLE (-6775 6350);
FORCEPROP 2 LAST CDS_SEC 1
J 0
(-6775 6350);
DISPLAY 1.021277 (-6775 6350);
DISPLAY INVISIBLE (-6775 6350);
FORCEPROP 1 LAST PATH I26
J 0
(-6775 6300);
DISPLAY 0.978723 (-6775 6300);
PAINT WHITE (-6775 6300);
DISPLAY INVISIBLE (-6775 6300);
FORCEADD UNIVERSAL_POWER..1
(-7275 6425);
FORCEPROP 3 LASTPIN (-7275 6375) SIG_NAME PVCCIN_CPU1\g
J 0
(-7265 6385);
DISPLAY 0.659574 (-7265 6385);
PAINT MONO (-7265 6385);
DISPLAY INVISIBLE (-7265 6385);
FORCEPROP 1 LAST HDL_POWER PVCCIN_CPU1
J 1
(-7075 6475);
DISPLAY 0.872340 (-7075 6475);
PAINT GREEN (-7075 6475);
FORCEPROP 2 LAST CDS_LIB logical_power
J 0
(-7275 6425);
DISPLAY INVISIBLE (-7275 6425);
FORCEPROP 1 LAST PATH I27
J 0
(-7225 6450);
DISPLAY 0.872340 (-7225 6450);
PAINT AQUA (-7225 6450);
DISPLAY INVISIBLE (-7225 6450);
FORCEADD Q_CAP..1
(-7275 6925);
FORCEPROP 1 LAST PART_NUMBER CH6101MEB03
J 0
(-7225 6775);
DISPLAY 0.638298 (-7225 6775);
DISPLAY INVISIBLE (-7225 6775);
FORCEPROP 1 LAST VOLTAGE 6.3V
J 0
(-7225 6925);
DISPLAY 0.638298 (-7225 6925);
FORCEPROP 1 LAST TOLERANCE 20%
J 0
(-7225 6875);
DISPLAY 0.638298 (-7225 6875);
FORCEPROP 1 LAST VALUE 10UF
J 0
(-7225 6975);
DISPLAY 0.638298 (-7225 6975);
FORCEPROP 1 LAST PACK_TYPE C0402
J 0
(-7225 6725);
DISPLAY 0.638298 (-7225 6725);
FORCEPROP 1 LAST MATERIAL X6S
J 0
(-7225 6825);
DISPLAY 0.638298 (-7225 6825);
FORCEPROP 1 LAST $LOCATION C221
J 0
(-7225 7025);
DISPLAY 0.638298 (-7225 7025);
FORCEPROP 1 LASTPIN (-7275 7025) $PN 1
J 0
(-7265 7005);
DISPLAY 0.787234 (-7265 7005);
FORCEPROP 1 LASTPIN (-7275 6825) $PN 2
J 0
(-7265 6805);
DISPLAY 0.787234 (-7265 6805);
FORCEPROP 2 LAST CDS_LIB pure_quanta
J 0
(-7275 6925);
PAINT MONO (-7275 6925);
DISPLAY INVISIBLE (-7275 6925);
FORCEPROP 1 LAST $LOCATION C221
J 0
(-7225 7125);
DISPLAY 1.021277 (-7225 7125);
DISPLAY INVISIBLE (-7225 7125);
FORCEPROP 2 LAST CDS_LOCATION C221
J 0
(-7225 7125);
DISPLAY 1.021277 (-7225 7125);
DISPLAY INVISIBLE (-7225 7125);
FORCEPROP 2 LAST $SEC 1
J 0
(-7225 7125);
DISPLAY 0.680851 (-7225 7125);
PAINT MONO (-7225 7125);
DISPLAY INVISIBLE (-7225 7125);
FORCEPROP 2 LAST CDS_SEC 1
J 0
(-7225 7125);
DISPLAY 1.021277 (-7225 7125);
DISPLAY INVISIBLE (-7225 7125);
FORCEPROP 1 LAST PATH I28
J 0
(-7225 7075);
DISPLAY 0.978723 (-7225 7075);
PAINT WHITE (-7225 7075);
DISPLAY INVISIBLE (-7225 7075);
FORCEADD Q_CAP..1
(-6825 6925);
FORCEPROP 1 LAST PART_NUMBER CH6101MEB03
J 0
(-6775 6775);
DISPLAY 0.638298 (-6775 6775);
DISPLAY INVISIBLE (-6775 6775);
FORCEPROP 1 LAST VOLTAGE 6.3V
J 0
(-6775 6925);
DISPLAY 0.638298 (-6775 6925);
FORCEPROP 1 LAST TOLERANCE 20%
J 0
(-6775 6875);
DISPLAY 0.638298 (-6775 6875);
FORCEPROP 1 LAST VALUE 10UF
J 0
(-6775 6975);
DISPLAY 0.638298 (-6775 6975);
FORCEPROP 1 LAST PACK_TYPE C0402
J 0
(-6775 6725);
DISPLAY 0.638298 (-6775 6725);
FORCEPROP 1 LAST MATERIAL X6S
J 0
(-6775 6825);
DISPLAY 0.638298 (-6775 6825);
FORCEPROP 1 LAST $LOCATION C226
J 0
(-6775 7025);
DISPLAY 0.638298 (-6775 7025);
FORCEPROP 1 LASTPIN (-6825 7025) $PN 1
J 0
(-6815 7005);
DISPLAY 0.787234 (-6815 7005);
FORCEPROP 1 LASTPIN (-6825 6825) $PN 2
J 0
(-6815 6805);
DISPLAY 0.787234 (-6815 6805);
FORCEPROP 2 LAST CDS_LIB pure_quanta
J 0
(-6825 6925);
PAINT MONO (-6825 6925);
DISPLAY INVISIBLE (-6825 6925);
FORCEPROP 1 LAST $LOCATION C226
J 0
(-6775 7125);
DISPLAY 1.021277 (-6775 7125);
DISPLAY INVISIBLE (-6775 7125);
FORCEPROP 2 LAST CDS_LOCATION C226
J 0
(-6775 7125);
DISPLAY 1.021277 (-6775 7125);
DISPLAY INVISIBLE (-6775 7125);
FORCEPROP 2 LAST $SEC 1
J 0
(-6775 7125);
DISPLAY 0.680851 (-6775 7125);
PAINT MONO (-6775 7125);
DISPLAY INVISIBLE (-6775 7125);
FORCEPROP 2 LAST CDS_SEC 1
J 0
(-6775 7125);
DISPLAY 1.021277 (-6775 7125);
DISPLAY INVISIBLE (-6775 7125);
FORCEPROP 1 LAST PATH I29
J 0
(-6775 7075);
DISPLAY 0.978723 (-6775 7075);
PAINT WHITE (-6775 7075);
DISPLAY INVISIBLE (-6775 7075);
FORCEADD UNIVERSAL_POWER..1
(-7250 2500);
FORCEPROP 3 LASTPIN (-7250 2450) SIG_NAME PVCCFA_EHV_FIVRA_CPU1\g
J 0
(-7240 2460);
DISPLAY 0.659574 (-7240 2460);
PAINT MONO (-7240 2460);
DISPLAY INVISIBLE (-7240 2460);
FORCEPROP 1 LAST HDL_POWER PVCCFA_EHV_FIVRA_CPU1
J 1
(-6850 2550);
DISPLAY 0.872340 (-6850 2550);
PAINT GREEN (-6850 2550);
FORCEPROP 2 LAST CDS_LIB logical_power
J 0
(-7250 2500);
DISPLAY INVISIBLE (-7250 2500);
FORCEPROP 1 LAST PATH I3
J 0
(-7200 2525);
DISPLAY 0.872340 (-7200 2525);
PAINT AQUA (-7200 2525);
DISPLAY INVISIBLE (-7200 2525);
FORCEADD Q_CAP..1
(-6350 5400);
FORCEPROP 1 LAST PART_NUMBER CH6101MEB03
J 0
(-6300 5250);
DISPLAY 0.638298 (-6300 5250);
DISPLAY INVISIBLE (-6300 5250);
FORCEPROP 1 LAST VALUE 10UF
J 0
(-6300 5450);
DISPLAY 0.638298 (-6300 5450);
FORCEPROP 1 LAST VOLTAGE 6.3V
J 0
(-6300 5400);
DISPLAY 0.638298 (-6300 5400);
FORCEPROP 1 LAST TOLERANCE 20%
J 0
(-6300 5350);
DISPLAY 0.638298 (-6300 5350);
FORCEPROP 1 LAST MATERIAL X6S
J 0
(-6300 5300);
DISPLAY 0.638298 (-6300 5300);
FORCEPROP 1 LAST PACK_TYPE C0402
J 0
(-6300 5200);
DISPLAY 0.638298 (-6300 5200);
FORCEPROP 1 LAST $LOCATION C233
J 0
(-6300 5500);
DISPLAY 0.638298 (-6300 5500);
FORCEPROP 1 LASTPIN (-6350 5500) $PN 1
J 0
(-6340 5480);
DISPLAY 0.787234 (-6340 5480);
FORCEPROP 1 LASTPIN (-6350 5300) $PN 2
J 0
(-6340 5280);
DISPLAY 0.787234 (-6340 5280);
FORCEPROP 2 LAST CDS_LIB pure_quanta
J 0
(-6350 5400);
PAINT MONO (-6350 5400);
DISPLAY INVISIBLE (-6350 5400);
FORCEPROP 1 LAST $LOCATION C233
J 0
(-6300 5600);
DISPLAY 1.021277 (-6300 5600);
DISPLAY INVISIBLE (-6300 5600);
FORCEPROP 2 LAST CDS_LOCATION C233
J 0
(-6300 5600);
DISPLAY 1.021277 (-6300 5600);
DISPLAY INVISIBLE (-6300 5600);
FORCEPROP 2 LAST $SEC 1
J 0
(-6300 5600);
DISPLAY 0.680851 (-6300 5600);
PAINT MONO (-6300 5600);
DISPLAY INVISIBLE (-6300 5600);
FORCEPROP 2 LAST CDS_SEC 1
J 0
(-6300 5600);
DISPLAY 1.021277 (-6300 5600);
DISPLAY INVISIBLE (-6300 5600);
FORCEPROP 1 LAST PATH I30
J 0
(-6300 5550);
DISPLAY 0.978723 (-6300 5550);
PAINT WHITE (-6300 5550);
DISPLAY INVISIBLE (-6300 5550);
FORCEADD Q_CAP..1
(-5900 5400);
FORCEPROP 1 LAST PART_NUMBER CH6101MEB03
J 0
(-5850 5250);
DISPLAY 0.638298 (-5850 5250);
DISPLAY INVISIBLE (-5850 5250);
FORCEPROP 1 LAST PACK_TYPE C0402
J 0
(-5850 5200);
DISPLAY 0.638298 (-5850 5200);
FORCEPROP 1 LAST TOLERANCE 20%
J 0
(-5850 5350);
DISPLAY 0.638298 (-5850 5350);
FORCEPROP 1 LAST VOLTAGE 6.3V
J 0
(-5850 5400);
DISPLAY 0.638298 (-5850 5400);
FORCEPROP 1 LAST MATERIAL X6S
J 0
(-5850 5300);
DISPLAY 0.638298 (-5850 5300);
FORCEPROP 1 LAST VALUE 10UF
J 0
(-5850 5450);
DISPLAY 0.638298 (-5850 5450);
FORCEPROP 1 LAST $LOCATION C238
J 0
(-5850 5500);
DISPLAY 0.638298 (-5850 5500);
FORCEPROP 1 LASTPIN (-5900 5500) $PN 1
J 0
(-5890 5480);
DISPLAY 0.787234 (-5890 5480);
FORCEPROP 1 LASTPIN (-5900 5300) $PN 2
J 0
(-5890 5280);
DISPLAY 0.787234 (-5890 5280);
FORCEPROP 2 LAST CDS_LIB pure_quanta
J 0
(-5900 5400);
PAINT MONO (-5900 5400);
DISPLAY INVISIBLE (-5900 5400);
FORCEPROP 1 LAST $LOCATION C238
J 0
(-5850 5600);
DISPLAY 1.021277 (-5850 5600);
DISPLAY INVISIBLE (-5850 5600);
FORCEPROP 2 LAST CDS_LOCATION C238
J 0
(-5850 5600);
DISPLAY 1.021277 (-5850 5600);
DISPLAY INVISIBLE (-5850 5600);
FORCEPROP 2 LAST $SEC 1
J 0
(-5850 5600);
DISPLAY 0.680851 (-5850 5600);
PAINT MONO (-5850 5600);
DISPLAY INVISIBLE (-5850 5600);
FORCEPROP 2 LAST CDS_SEC 1
J 0
(-5850 5600);
DISPLAY 1.021277 (-5850 5600);
DISPLAY INVISIBLE (-5850 5600);
FORCEPROP 1 LAST PATH I31
J 0
(-5850 5550);
DISPLAY 0.978723 (-5850 5550);
PAINT WHITE (-5850 5550);
DISPLAY INVISIBLE (-5850 5550);
FORCEADD Q_CAP..1
(-6375 6150);
FORCEPROP 1 LAST PART_NUMBER CH6101MEB03
J 0
(-6325 6000);
DISPLAY 0.638298 (-6325 6000);
DISPLAY INVISIBLE (-6325 6000);
FORCEPROP 1 LAST VOLTAGE 6.3V
J 0
(-6325 6150);
DISPLAY 0.638298 (-6325 6150);
FORCEPROP 1 LAST VALUE 10UF
J 0
(-6325 6200);
DISPLAY 0.638298 (-6325 6200);
FORCEPROP 1 LAST TOLERANCE 20%
J 0
(-6325 6100);
DISPLAY 0.638298 (-6325 6100);
FORCEPROP 1 LAST PACK_TYPE C0402
J 0
(-6325 5950);
DISPLAY 0.638298 (-6325 5950);
FORCEPROP 1 LAST MATERIAL X6S
J 0
(-6325 6050);
DISPLAY 0.638298 (-6325 6050);
FORCEPROP 1 LAST $LOCATION C232
J 0
(-6325 6250);
DISPLAY 0.638298 (-6325 6250);
FORCEPROP 1 LASTPIN (-6375 6250) $PN 1
J 0
(-6365 6230);
DISPLAY 0.787234 (-6365 6230);
FORCEPROP 1 LASTPIN (-6375 6050) $PN 2
J 0
(-6365 6030);
DISPLAY 0.787234 (-6365 6030);
FORCEPROP 2 LAST CDS_LIB pure_quanta
J 0
(-6375 6150);
PAINT MONO (-6375 6150);
DISPLAY INVISIBLE (-6375 6150);
FORCEPROP 1 LAST $LOCATION C232
J 0
(-6325 6350);
DISPLAY 1.021277 (-6325 6350);
DISPLAY INVISIBLE (-6325 6350);
FORCEPROP 2 LAST CDS_LOCATION C232
J 0
(-6325 6350);
DISPLAY 1.021277 (-6325 6350);
DISPLAY INVISIBLE (-6325 6350);
FORCEPROP 2 LAST $SEC 1
J 0
(-6325 6350);
DISPLAY 0.680851 (-6325 6350);
PAINT MONO (-6325 6350);
DISPLAY INVISIBLE (-6325 6350);
FORCEPROP 2 LAST CDS_SEC 1
J 0
(-6325 6350);
DISPLAY 1.021277 (-6325 6350);
DISPLAY INVISIBLE (-6325 6350);
FORCEPROP 1 LAST PATH I32
J 0
(-6325 6300);
DISPLAY 0.978723 (-6325 6300);
PAINT WHITE (-6325 6300);
DISPLAY INVISIBLE (-6325 6300);
FORCEADD Q_CAP..1
(-6375 6925);
FORCEPROP 1 LAST PART_NUMBER CH6101MEB03
J 0
(-6325 6775);
DISPLAY 0.638298 (-6325 6775);
DISPLAY INVISIBLE (-6325 6775);
FORCEPROP 1 LAST VOLTAGE 6.3V
J 0
(-6325 6925);
DISPLAY 0.638298 (-6325 6925);
FORCEPROP 1 LAST TOLERANCE 20%
J 0
(-6325 6875);
DISPLAY 0.638298 (-6325 6875);
FORCEPROP 1 LAST VALUE 10UF
J 0
(-6325 6975);
DISPLAY 0.638298 (-6325 6975);
FORCEPROP 1 LAST PACK_TYPE C0402
J 0
(-6325 6725);
DISPLAY 0.638298 (-6325 6725);
FORCEPROP 1 LAST MATERIAL X6S
J 0
(-6325 6825);
DISPLAY 0.638298 (-6325 6825);
FORCEPROP 1 LAST $LOCATION C231
J 0
(-6325 7025);
DISPLAY 0.638298 (-6325 7025);
FORCEPROP 1 LASTPIN (-6375 7025) $PN 1
J 0
(-6365 7005);
DISPLAY 0.787234 (-6365 7005);
FORCEPROP 1 LASTPIN (-6375 6825) $PN 2
J 0
(-6365 6805);
DISPLAY 0.787234 (-6365 6805);
FORCEPROP 2 LAST CDS_LIB pure_quanta
J 0
(-6375 6925);
PAINT MONO (-6375 6925);
DISPLAY INVISIBLE (-6375 6925);
FORCEPROP 1 LAST $LOCATION C231
J 0
(-6325 7125);
DISPLAY 1.021277 (-6325 7125);
DISPLAY INVISIBLE (-6325 7125);
FORCEPROP 2 LAST CDS_LOCATION C231
J 0
(-6325 7125);
DISPLAY 1.021277 (-6325 7125);
DISPLAY INVISIBLE (-6325 7125);
FORCEPROP 2 LAST $SEC 1
J 0
(-6325 7125);
DISPLAY 0.680851 (-6325 7125);
PAINT MONO (-6325 7125);
DISPLAY INVISIBLE (-6325 7125);
FORCEPROP 2 LAST CDS_SEC 1
J 0
(-6325 7125);
DISPLAY 1.021277 (-6325 7125);
DISPLAY INVISIBLE (-6325 7125);
FORCEPROP 1 LAST PATH I33
J 0
(-6325 7075);
DISPLAY 0.978723 (-6325 7075);
PAINT WHITE (-6325 7075);
DISPLAY INVISIBLE (-6325 7075);
FORCEADD Q_CAP..1
(-5925 6150);
FORCEPROP 1 LAST PART_NUMBER CH6101MEB03
J 0
(-5875 6000);
DISPLAY 0.638298 (-5875 6000);
DISPLAY INVISIBLE (-5875 6000);
FORCEPROP 1 LAST TOLERANCE 20%
J 0
(-5875 6100);
DISPLAY 0.638298 (-5875 6100);
FORCEPROP 1 LAST VALUE 10UF
J 0
(-5875 6200);
DISPLAY 0.638298 (-5875 6200);
FORCEPROP 1 LAST VOLTAGE 6.3V
J 0
(-5875 6150);
DISPLAY 0.638298 (-5875 6150);
FORCEPROP 1 LAST MATERIAL X6S
J 0
(-5875 6050);
DISPLAY 0.638298 (-5875 6050);
FORCEPROP 1 LAST PACK_TYPE C0402
J 0
(-5875 5950);
DISPLAY 0.638298 (-5875 5950);
FORCEPROP 1 LAST $LOCATION C237
J 0
(-5875 6250);
DISPLAY 0.638298 (-5875 6250);
FORCEPROP 1 LASTPIN (-5925 6250) $PN 1
J 0
(-5915 6230);
DISPLAY 0.787234 (-5915 6230);
FORCEPROP 1 LASTPIN (-5925 6050) $PN 2
J 0
(-5915 6030);
DISPLAY 0.787234 (-5915 6030);
FORCEPROP 2 LAST CDS_LIB pure_quanta
J 0
(-5925 6150);
PAINT MONO (-5925 6150);
DISPLAY INVISIBLE (-5925 6150);
FORCEPROP 1 LAST $LOCATION C237
J 0
(-5875 6350);
DISPLAY 1.021277 (-5875 6350);
DISPLAY INVISIBLE (-5875 6350);
FORCEPROP 2 LAST CDS_LOCATION C237
J 0
(-5875 6350);
DISPLAY 1.021277 (-5875 6350);
DISPLAY INVISIBLE (-5875 6350);
FORCEPROP 2 LAST $SEC 1
J 0
(-5875 6350);
DISPLAY 0.680851 (-5875 6350);
PAINT MONO (-5875 6350);
DISPLAY INVISIBLE (-5875 6350);
FORCEPROP 2 LAST CDS_SEC 1
J 0
(-5875 6350);
DISPLAY 1.021277 (-5875 6350);
DISPLAY INVISIBLE (-5875 6350);
FORCEPROP 1 LAST PATH I34
J 0
(-5875 6300);
DISPLAY 0.978723 (-5875 6300);
PAINT WHITE (-5875 6300);
DISPLAY INVISIBLE (-5875 6300);
FORCEADD Q_CAP..1
(-5925 6925);
FORCEPROP 1 LAST PART_NUMBER CH6101MEB03
J 0
(-5875 6775);
DISPLAY 0.638298 (-5875 6775);
DISPLAY INVISIBLE (-5875 6775);
FORCEPROP 1 LAST TOLERANCE 20%
J 0
(-5875 6875);
DISPLAY 0.638298 (-5875 6875);
FORCEPROP 1 LAST VOLTAGE 6.3V
J 0
(-5875 6925);
DISPLAY 0.638298 (-5875 6925);
FORCEPROP 1 LAST PACK_TYPE C0402
J 0
(-5875 6725);
DISPLAY 0.638298 (-5875 6725);
FORCEPROP 1 LAST MATERIAL X6S
J 0
(-5875 6825);
DISPLAY 0.638298 (-5875 6825);
FORCEPROP 1 LAST VALUE 10UF
J 0
(-5875 6975);
DISPLAY 0.638298 (-5875 6975);
FORCEPROP 1 LAST $LOCATION C236
J 0
(-5875 7025);
DISPLAY 0.638298 (-5875 7025);
FORCEPROP 1 LASTPIN (-5925 7025) $PN 1
J 0
(-5915 7005);
DISPLAY 0.787234 (-5915 7005);
FORCEPROP 1 LASTPIN (-5925 6825) $PN 2
J 0
(-5915 6805);
DISPLAY 0.787234 (-5915 6805);
FORCEPROP 2 LAST CDS_LIB pure_quanta
J 0
(-5925 6925);
PAINT MONO (-5925 6925);
DISPLAY INVISIBLE (-5925 6925);
FORCEPROP 1 LAST $LOCATION C236
J 0
(-5875 7125);
DISPLAY 1.021277 (-5875 7125);
DISPLAY INVISIBLE (-5875 7125);
FORCEPROP 2 LAST CDS_LOCATION C236
J 0
(-5875 7125);
DISPLAY 1.021277 (-5875 7125);
DISPLAY INVISIBLE (-5875 7125);
FORCEPROP 2 LAST $SEC 1
J 0
(-5875 7125);
DISPLAY 0.680851 (-5875 7125);
PAINT MONO (-5875 7125);
DISPLAY INVISIBLE (-5875 7125);
FORCEPROP 2 LAST CDS_SEC 1
J 0
(-5875 7125);
DISPLAY 1.021277 (-5875 7125);
DISPLAY INVISIBLE (-5875 7125);
FORCEPROP 1 LAST PATH I35
J 0
(-5875 7075);
DISPLAY 0.978723 (-5875 7075);
PAINT WHITE (-5875 7075);
DISPLAY INVISIBLE (-5875 7075);
FORCEADD UNIVERSAL_POWER..1
(-7275 7200);
FORCEPROP 3 LASTPIN (-7275 7150) SIG_NAME PVCCIN_CPU1\g
J 0
(-7265 7160);
DISPLAY 0.659574 (-7265 7160);
PAINT MONO (-7265 7160);
DISPLAY INVISIBLE (-7265 7160);
FORCEPROP 1 LAST HDL_POWER PVCCIN_CPU1
J 1
(-7075 7250);
DISPLAY 0.872340 (-7075 7250);
PAINT GREEN (-7075 7250);
FORCEPROP 2 LAST CDS_LIB logical_power
J 0
(-7275 7200);
DISPLAY INVISIBLE (-7275 7200);
FORCEPROP 1 LAST PATH I36
J 0
(-7225 7225);
DISPLAY 0.872340 (-7225 7225);
PAINT AQUA (-7225 7225);
DISPLAY INVISIBLE (-7225 7225);
FORCEADD Q_CAP..1
(-5450 2225);
FORCEPROP 1 LAST PART_NUMBER CH622KMEB01
J 0
(-5400 2075);
DISPLAY 0.638298 (-5400 2075);
DISPLAY INVISIBLE (-5400 2075);
FORCEPROP 1 LAST VOLTAGE 4V
J 0
(-5400 2225);
DISPLAY 0.638298 (-5400 2225);
FORCEPROP 1 LAST TOLERANCE 20%
J 0
(-5400 2175);
DISPLAY 0.638298 (-5400 2175);
FORCEPROP 1 LAST PACK_TYPE C0402
J 0
(-5400 2025);
DISPLAY 0.638298 (-5400 2025);
FORCEPROP 1 LAST VALUE 22UF
J 0
(-5400 2275);
DISPLAY 0.638298 (-5400 2275);
FORCEPROP 1 LAST MATERIAL X6S
J 0
(-5400 2125);
DISPLAY 0.638298 (-5400 2125);
FORCEPROP 1 LAST $LOCATION C431
J 0
(-5400 2325);
DISPLAY 0.978723 (-5400 2325);
FORCEPROP 1 LASTPIN (-5450 2325) $PN 1
J 0
(-5440 2305);
DISPLAY 0.787234 (-5440 2305);
FORCEPROP 1 LASTPIN (-5450 2125) $PN 2
J 0
(-5440 2105);
DISPLAY 0.787234 (-5440 2105);
FORCEPROP 2 LAST CDS_LIB pure_quanta
J 0
(-5450 2225);
PAINT MONO (-5450 2225);
DISPLAY INVISIBLE (-5450 2225);
FORCEPROP 2 LAST CDS_LOCATION C431
J 0
(-5400 2425);
DISPLAY 1.021277 (-5400 2425);
DISPLAY INVISIBLE (-5400 2425);
FORCEPROP 2 LAST $SEC 1
J 0
(-5400 2425);
DISPLAY 0.680851 (-5400 2425);
PAINT MONO (-5400 2425);
DISPLAY INVISIBLE (-5400 2425);
FORCEPROP 2 LAST CDS_SEC 1
J 0
(-5400 2425);
DISPLAY 1.021277 (-5400 2425);
DISPLAY INVISIBLE (-5400 2425);
FORCEPROP 1 LAST PATH I37
J 0
(-5400 2375);
DISPLAY 0.978723 (-5400 2375);
PAINT WHITE (-5400 2375);
DISPLAY INVISIBLE (-5400 2375);
FORCEADD Q_CAP..1
(-5000 2225);
FORCEPROP 1 LAST PART_NUMBER CH622KMEB01
J 0
(-4950 2075);
DISPLAY 0.638298 (-4950 2075);
DISPLAY INVISIBLE (-4950 2075);
FORCEPROP 1 LAST TOLERANCE 20%
J 0
(-4950 2175);
DISPLAY 0.638298 (-4950 2175);
FORCEPROP 1 LAST VOLTAGE 4V
J 0
(-4950 2225);
DISPLAY 0.638298 (-4950 2225);
FORCEPROP 1 LAST VALUE 22UF
J 0
(-4950 2275);
DISPLAY 0.638298 (-4950 2275);
FORCEPROP 1 LAST PACK_TYPE C0402
J 0
(-4950 2025);
DISPLAY 0.638298 (-4950 2025);
FORCEPROP 1 LAST MATERIAL X6S
J 0
(-4950 2125);
DISPLAY 0.638298 (-4950 2125);
FORCEPROP 1 LAST $LOCATION C433
J 0
(-4950 2325);
DISPLAY 0.978723 (-4950 2325);
FORCEPROP 1 LASTPIN (-5000 2325) $PN 1
J 0
(-4990 2305);
DISPLAY 0.787234 (-4990 2305);
FORCEPROP 1 LASTPIN (-5000 2125) $PN 2
J 0
(-4990 2105);
DISPLAY 0.787234 (-4990 2105);
FORCEPROP 2 LAST CDS_LIB pure_quanta
J 0
(-5000 2225);
PAINT MONO (-5000 2225);
DISPLAY INVISIBLE (-5000 2225);
FORCEPROP 2 LAST CDS_LOCATION C433
J 0
(-4950 2425);
DISPLAY 1.021277 (-4950 2425);
DISPLAY INVISIBLE (-4950 2425);
FORCEPROP 2 LAST $SEC 1
J 0
(-4950 2425);
DISPLAY 0.680851 (-4950 2425);
PAINT MONO (-4950 2425);
DISPLAY INVISIBLE (-4950 2425);
FORCEPROP 2 LAST CDS_SEC 1
J 0
(-4950 2425);
DISPLAY 1.021277 (-4950 2425);
DISPLAY INVISIBLE (-4950 2425);
FORCEPROP 1 LAST PATH I38
J 0
(-4950 2375);
DISPLAY 0.978723 (-4950 2375);
PAINT WHITE (-4950 2375);
DISPLAY INVISIBLE (-4950 2375);
FORCEADD Q_CAP..1
(-4550 2225);
FORCEPROP 1 LAST PART_NUMBER CH622KMEB01
J 0
(-4500 2075);
DISPLAY 0.638298 (-4500 2075);
DISPLAY INVISIBLE (-4500 2075);
FORCEPROP 1 LAST VOLTAGE 4V
J 0
(-4500 2225);
DISPLAY 0.638298 (-4500 2225);
FORCEPROP 1 LAST TOLERANCE 20%
J 0
(-4500 2175);
DISPLAY 0.638298 (-4500 2175);
FORCEPROP 1 LAST VALUE 22UF
J 0
(-4500 2275);
DISPLAY 0.638298 (-4500 2275);
FORCEPROP 1 LAST MATERIAL X6S
J 0
(-4500 2125);
DISPLAY 0.638298 (-4500 2125);
FORCEPROP 1 LAST PACK_TYPE C0402
J 0
(-4500 2025);
DISPLAY 0.638298 (-4500 2025);
FORCEPROP 1 LAST $LOCATION C435
J 0
(-4500 2325);
DISPLAY 0.978723 (-4500 2325);
FORCEPROP 1 LASTPIN (-4550 2325) $PN 1
J 0
(-4540 2305);
DISPLAY 0.787234 (-4540 2305);
FORCEPROP 1 LASTPIN (-4550 2125) $PN 2
J 0
(-4540 2105);
DISPLAY 0.787234 (-4540 2105);
FORCEPROP 2 LAST CDS_LIB pure_quanta
J 0
(-4550 2225);
PAINT MONO (-4550 2225);
DISPLAY INVISIBLE (-4550 2225);
FORCEPROP 2 LAST CDS_LOCATION C435
J 0
(-4500 2425);
DISPLAY 1.021277 (-4500 2425);
DISPLAY INVISIBLE (-4500 2425);
FORCEPROP 2 LAST $SEC 1
J 0
(-4500 2425);
DISPLAY 0.680851 (-4500 2425);
PAINT MONO (-4500 2425);
DISPLAY INVISIBLE (-4500 2425);
FORCEPROP 2 LAST CDS_SEC 1
J 0
(-4500 2425);
DISPLAY 1.021277 (-4500 2425);
DISPLAY INVISIBLE (-4500 2425);
FORCEPROP 1 LAST PATH I39
J 0
(-4500 2375);
DISPLAY 0.978723 (-4500 2375);
PAINT WHITE (-4500 2375);
DISPLAY INVISIBLE (-4500 2375);
FORCEADD Q_CAP..1
(-6350 2225);
FORCEPROP 1 LAST PART_NUMBER CH622KMEB01
J 0
(-6300 2075);
DISPLAY 0.638298 (-6300 2075);
DISPLAY INVISIBLE (-6300 2075);
FORCEPROP 1 LAST TOLERANCE 20%
J 0
(-6300 2175);
DISPLAY 0.638298 (-6300 2175);
FORCEPROP 1 LAST VOLTAGE 4V
J 0
(-6300 2225);
DISPLAY 0.638298 (-6300 2225);
FORCEPROP 1 LAST MATERIAL X6S
J 0
(-6300 2125);
DISPLAY 0.638298 (-6300 2125);
FORCEPROP 1 LAST VALUE 22UF
J 0
(-6300 2275);
DISPLAY 0.638298 (-6300 2275);
FORCEPROP 1 LAST PACK_TYPE C0402
J 0
(-6300 2025);
DISPLAY 0.638298 (-6300 2025);
FORCEPROP 1 LAST $LOCATION C428
J 0
(-6300 2325);
DISPLAY 0.978723 (-6300 2325);
FORCEPROP 1 LASTPIN (-6350 2325) $PN 1
J 0
(-6340 2305);
DISPLAY 0.787234 (-6340 2305);
FORCEPROP 1 LASTPIN (-6350 2125) $PN 2
J 0
(-6340 2105);
DISPLAY 0.787234 (-6340 2105);
FORCEPROP 2 LAST CDS_LIB pure_quanta
J 0
(-6350 2225);
PAINT MONO (-6350 2225);
DISPLAY INVISIBLE (-6350 2225);
FORCEPROP 2 LAST CDS_LOCATION C428
J 0
(-6300 2425);
DISPLAY 1.021277 (-6300 2425);
DISPLAY INVISIBLE (-6300 2425);
FORCEPROP 2 LAST $SEC 1
J 0
(-6300 2425);
DISPLAY 0.680851 (-6300 2425);
PAINT MONO (-6300 2425);
DISPLAY INVISIBLE (-6300 2425);
FORCEPROP 2 LAST CDS_SEC 1
J 0
(-6300 2425);
DISPLAY 1.021277 (-6300 2425);
DISPLAY INVISIBLE (-6300 2425);
FORCEPROP 1 LAST PATH I4
J 0
(-6300 2375);
DISPLAY 0.978723 (-6300 2375);
PAINT WHITE (-6300 2375);
DISPLAY INVISIBLE (-6300 2375);
FORCEADD Q_CAP..1
(-4100 2225);
FORCEPROP 1 LAST PART_NUMBER CH622KMEB01
J 0
(-4050 2075);
DISPLAY 0.638298 (-4050 2075);
DISPLAY INVISIBLE (-4050 2075);
FORCEPROP 1 LAST VOLTAGE 4V
J 0
(-4050 2225);
DISPLAY 0.638298 (-4050 2225);
FORCEPROP 1 LAST TOLERANCE 20%
J 0
(-4050 2175);
DISPLAY 0.638298 (-4050 2175);
FORCEPROP 1 LAST VALUE 22UF
J 0
(-4050 2275);
DISPLAY 0.638298 (-4050 2275);
FORCEPROP 1 LAST PACK_TYPE C0402
J 0
(-4050 2025);
DISPLAY 0.638298 (-4050 2025);
FORCEPROP 1 LAST MATERIAL X6S
J 0
(-4050 2125);
DISPLAY 0.638298 (-4050 2125);
FORCEPROP 1 LAST $LOCATION C437
J 0
(-4050 2325);
DISPLAY 0.978723 (-4050 2325);
FORCEPROP 1 LASTPIN (-4100 2325) $PN 1
J 0
(-4090 2305);
DISPLAY 0.787234 (-4090 2305);
FORCEPROP 1 LASTPIN (-4100 2125) $PN 2
J 0
(-4090 2105);
DISPLAY 0.787234 (-4090 2105);
FORCEPROP 2 LAST CDS_LIB pure_quanta
J 0
(-4100 2225);
PAINT MONO (-4100 2225);
DISPLAY INVISIBLE (-4100 2225);
FORCEPROP 2 LAST CDS_LOCATION C437
J 0
(-4050 2425);
DISPLAY 1.021277 (-4050 2425);
DISPLAY INVISIBLE (-4050 2425);
FORCEPROP 2 LAST $SEC 1
J 0
(-4050 2425);
DISPLAY 0.680851 (-4050 2425);
PAINT MONO (-4050 2425);
DISPLAY INVISIBLE (-4050 2425);
FORCEPROP 2 LAST CDS_SEC 1
J 0
(-4050 2425);
DISPLAY 1.021277 (-4050 2425);
DISPLAY INVISIBLE (-4050 2425);
FORCEPROP 1 LAST PATH I40
J 0
(-4050 2375);
DISPLAY 0.978723 (-4050 2375);
PAINT WHITE (-4050 2375);
DISPLAY INVISIBLE (-4050 2375);
FORCEADD Q_CAP..1
(-5450 3850);
FORCEPROP 1 LAST PART_NUMBER CH647KMEA04
J 0
(-5400 3700);
DISPLAY 0.638298 (-5400 3700);
DISPLAY INVISIBLE (-5400 3700);
FORCEPROP 1 LAST TOLERANCE 20%
J 0
(-5400 3800);
DISPLAY 0.638298 (-5400 3800);
FORCEPROP 1 LAST VOLTAGE 4V
J 0
(-5400 3850);
DISPLAY 0.638298 (-5400 3850);
FORCEPROP 1 LAST PACK_TYPE C0805
J 0
(-5400 3650);
DISPLAY 0.638298 (-5400 3650);
FORCEPROP 1 LAST MATERIAL X6S
J 0
(-5400 3750);
DISPLAY 0.638298 (-5400 3750);
FORCEPROP 1 LAST VALUE 47UF
J 0
(-5400 3900);
DISPLAY 0.638298 (-5400 3900);
FORCEPROP 1 LAST $LOCATION C245
J 0
(-5400 3950);
DISPLAY 0.638298 (-5400 3950);
FORCEPROP 1 LASTPIN (-5450 3950) $PN 1
J 0
(-5440 3930);
DISPLAY 0.787234 (-5440 3930);
FORCEPROP 1 LASTPIN (-5450 3750) $PN 2
J 0
(-5440 3730);
DISPLAY 0.787234 (-5440 3730);
FORCEPROP 2 LAST CDS_LIB pure_quanta
J 0
(-5450 3850);
PAINT MONO (-5450 3850);
DISPLAY INVISIBLE (-5450 3850);
FORCEPROP 1 LAST $LOCATION C245
J 0
(-5400 4050);
DISPLAY 1.021277 (-5400 4050);
DISPLAY INVISIBLE (-5400 4050);
FORCEPROP 2 LAST CDS_LOCATION C245
J 0
(-5400 4050);
DISPLAY 1.021277 (-5400 4050);
DISPLAY INVISIBLE (-5400 4050);
FORCEPROP 2 LAST $SEC 1
J 0
(-5400 4050);
DISPLAY 0.680851 (-5400 4050);
PAINT MONO (-5400 4050);
DISPLAY INVISIBLE (-5400 4050);
FORCEPROP 2 LAST CDS_SEC 1
J 0
(-5400 4050);
DISPLAY 1.021277 (-5400 4050);
DISPLAY INVISIBLE (-5400 4050);
FORCEPROP 1 LAST PATH I41
J 0
(-5400 4000);
DISPLAY 0.978723 (-5400 4000);
PAINT WHITE (-5400 4000);
DISPLAY INVISIBLE (-5400 4000);
FORCEADD Q_CAP..1
(-5000 3050);
FORCEPROP 1 LAST PART_NUMBER CH622KMEB01
J 0
(-4950 2900);
DISPLAY 0.638298 (-4950 2900);
DISPLAY INVISIBLE (-4950 2900);
FORCEPROP 1 LAST TOLERANCE 20%
J 0
(-4950 3000);
DISPLAY 0.638298 (-4950 3000);
FORCEPROP 1 LAST VALUE 22UF
J 0
(-4950 3100);
DISPLAY 0.638298 (-4950 3100);
FORCEPROP 1 LAST VOLTAGE 4V
J 0
(-4950 3050);
DISPLAY 0.638298 (-4950 3050);
FORCEPROP 1 LAST MATERIAL X6S
J 0
(-4950 2950);
DISPLAY 0.638298 (-4950 2950);
FORCEPROP 1 LAST PACK_TYPE C0402
J 0
(-4950 2850);
DISPLAY 0.638298 (-4950 2850);
FORCEPROP 1 LAST $LOCATION C432
J 0
(-4950 3150);
DISPLAY 0.978723 (-4950 3150);
FORCEPROP 1 LASTPIN (-5000 3150) $PN 1
J 0
(-4990 3130);
DISPLAY 0.787234 (-4990 3130);
FORCEPROP 1 LASTPIN (-5000 2950) $PN 2
J 0
(-4990 2930);
DISPLAY 0.787234 (-4990 2930);
FORCEPROP 2 LAST CDS_LIB pure_quanta
J 0
(-5000 3050);
PAINT MONO (-5000 3050);
DISPLAY INVISIBLE (-5000 3050);
FORCEPROP 2 LAST CDS_LOCATION C432
J 0
(-4950 3250);
DISPLAY 1.021277 (-4950 3250);
DISPLAY INVISIBLE (-4950 3250);
FORCEPROP 2 LAST $SEC 1
J 0
(-4950 3250);
DISPLAY 0.680851 (-4950 3250);
PAINT MONO (-4950 3250);
DISPLAY INVISIBLE (-4950 3250);
FORCEPROP 2 LAST CDS_SEC 1
J 0
(-4950 3250);
DISPLAY 1.021277 (-4950 3250);
DISPLAY INVISIBLE (-4950 3250);
FORCEPROP 1 LAST PATH I42
J 0
(-4950 3200);
DISPLAY 0.978723 (-4950 3200);
PAINT WHITE (-4950 3200);
DISPLAY INVISIBLE (-4950 3200);
FORCEADD UNIVERSAL_POWER..1
(-5000 3325);
FORCEPROP 3 LASTPIN (-5000 3275) SIG_NAME PVCCINFAON_CPU1\g
J 0
(-4990 3285);
DISPLAY 0.659574 (-4990 3285);
PAINT MONO (-4990 3285);
DISPLAY INVISIBLE (-4990 3285);
FORCEPROP 1 LAST HDL_POWER PVCCINFAON_CPU1
J 1
(-4750 3375);
DISPLAY 0.872340 (-4750 3375);
PAINT GREEN (-4750 3375);
FORCEPROP 2 LAST CDS_LIB logical_power
J 0
(-5000 3325);
PAINT MONO (-5000 3325);
DISPLAY INVISIBLE (-5000 3325);
FORCEPROP 1 LAST PATH I43
J 0
(-4950 3350);
DISPLAY 0.872340 (-4950 3350);
PAINT AQUA (-4950 3350);
DISPLAY INVISIBLE (-4950 3350);
FORCEADD Q_CAP..1
(-5000 3850);
FORCEPROP 1 LAST PART_NUMBER CH647KMEA04
J 0
(-4950 3700);
DISPLAY 0.638298 (-4950 3700);
DISPLAY INVISIBLE (-4950 3700);
FORCEPROP 1 LAST TOLERANCE 20%
J 0
(-4950 3800);
DISPLAY 0.638298 (-4950 3800);
FORCEPROP 1 LAST VOLTAGE 4V
J 0
(-4950 3850);
DISPLAY 0.638298 (-4950 3850);
FORCEPROP 1 LAST PACK_TYPE C0805
J 0
(-4950 3650);
DISPLAY 0.638298 (-4950 3650);
FORCEPROP 1 LAST MATERIAL X6S
J 0
(-4950 3750);
DISPLAY 0.638298 (-4950 3750);
FORCEPROP 1 LAST VALUE 47UF
J 0
(-4950 3900);
DISPLAY 0.638298 (-4950 3900);
FORCEPROP 1 LAST $LOCATION C250
J 0
(-4950 3950);
DISPLAY 0.638298 (-4950 3950);
FORCEPROP 1 LASTPIN (-5000 3950) $PN 1
J 0
(-4990 3930);
DISPLAY 0.787234 (-4990 3930);
FORCEPROP 1 LASTPIN (-5000 3750) $PN 2
J 0
(-4990 3730);
DISPLAY 0.787234 (-4990 3730);
FORCEPROP 2 LAST CDS_LIB pure_quanta
J 0
(-5000 3850);
PAINT MONO (-5000 3850);
DISPLAY INVISIBLE (-5000 3850);
FORCEPROP 1 LAST $LOCATION C250
J 0
(-4950 4050);
DISPLAY 1.021277 (-4950 4050);
DISPLAY INVISIBLE (-4950 4050);
FORCEPROP 2 LAST CDS_LOCATION C250
J 0
(-4950 4050);
DISPLAY 1.021277 (-4950 4050);
DISPLAY INVISIBLE (-4950 4050);
FORCEPROP 2 LAST $SEC 1
J 0
(-4950 4050);
DISPLAY 0.680851 (-4950 4050);
PAINT MONO (-4950 4050);
DISPLAY INVISIBLE (-4950 4050);
FORCEPROP 2 LAST CDS_SEC 1
J 0
(-4950 4050);
DISPLAY 1.021277 (-4950 4050);
DISPLAY INVISIBLE (-4950 4050);
FORCEPROP 1 LAST PATH I44
J 0
(-4950 4000);
DISPLAY 0.978723 (-4950 4000);
PAINT WHITE (-4950 4000);
DISPLAY INVISIBLE (-4950 4000);
FORCEADD Q_CAP..1
(-5450 4625);
FORCEPROP 1 LAST PART_NUMBER CH6101MEB03
J 0
(-5400 4475);
DISPLAY 0.638298 (-5400 4475);
DISPLAY INVISIBLE (-5400 4475);
FORCEPROP 1 LAST VALUE 10UF
J 0
(-5400 4675);
DISPLAY 0.638298 (-5400 4675);
FORCEPROP 1 LAST VOLTAGE 6.3V
J 0
(-5400 4625);
DISPLAY 0.638298 (-5400 4625);
FORCEPROP 1 LAST PACK_TYPE C0402
J 0
(-5400 4425);
DISPLAY 0.638298 (-5400 4425);
FORCEPROP 1 LAST TOLERANCE 20%
J 0
(-5400 4575);
DISPLAY 0.638298 (-5400 4575);
FORCEPROP 1 LAST MATERIAL X6S
J 0
(-5400 4525);
DISPLAY 0.638298 (-5400 4525);
FORCEPROP 1 LAST $LOCATION C244
J 0
(-5400 4725);
DISPLAY 0.638298 (-5400 4725);
FORCEPROP 1 LASTPIN (-5450 4725) $PN 1
J 0
(-5440 4705);
DISPLAY 0.787234 (-5440 4705);
FORCEPROP 1 LASTPIN (-5450 4525) $PN 2
J 0
(-5440 4505);
DISPLAY 0.787234 (-5440 4505);
FORCEPROP 2 LAST CDS_LIB pure_quanta
J 0
(-5450 4625);
PAINT MONO (-5450 4625);
DISPLAY INVISIBLE (-5450 4625);
FORCEPROP 1 LAST $LOCATION C244
J 0
(-5400 4825);
DISPLAY 1.021277 (-5400 4825);
DISPLAY INVISIBLE (-5400 4825);
FORCEPROP 2 LAST CDS_LOCATION C244
J 0
(-5400 4825);
DISPLAY 1.021277 (-5400 4825);
DISPLAY INVISIBLE (-5400 4825);
FORCEPROP 2 LAST $SEC 1
J 0
(-5400 4825);
DISPLAY 0.680851 (-5400 4825);
PAINT MONO (-5400 4825);
DISPLAY INVISIBLE (-5400 4825);
FORCEPROP 2 LAST CDS_SEC 1
J 0
(-5400 4825);
DISPLAY 1.021277 (-5400 4825);
DISPLAY INVISIBLE (-5400 4825);
FORCEPROP 1 LAST PATH I45
J 0
(-5400 4775);
DISPLAY 0.978723 (-5400 4775);
PAINT WHITE (-5400 4775);
DISPLAY INVISIBLE (-5400 4775);
FORCEADD Q_CAP..1
(-5000 4625);
FORCEPROP 1 LAST PART_NUMBER CH6101MEB03
J 0
(-4950 4475);
DISPLAY 0.638298 (-4950 4475);
DISPLAY INVISIBLE (-4950 4475);
FORCEPROP 1 LAST VALUE 10UF
J 0
(-4950 4675);
DISPLAY 0.638298 (-4950 4675);
FORCEPROP 1 LAST VOLTAGE 6.3V
J 0
(-4950 4625);
DISPLAY 0.638298 (-4950 4625);
FORCEPROP 1 LAST PACK_TYPE C0402
J 0
(-4950 4425);
DISPLAY 0.638298 (-4950 4425);
FORCEPROP 1 LAST MATERIAL X6S
J 0
(-4950 4525);
DISPLAY 0.638298 (-4950 4525);
FORCEPROP 1 LAST TOLERANCE 20%
J 0
(-4950 4575);
DISPLAY 0.638298 (-4950 4575);
FORCEPROP 1 LAST $LOCATION C249
J 0
(-4950 4725);
DISPLAY 0.638298 (-4950 4725);
FORCEPROP 1 LASTPIN (-5000 4725) $PN 1
J 0
(-4990 4705);
DISPLAY 0.787234 (-4990 4705);
FORCEPROP 1 LASTPIN (-5000 4525) $PN 2
J 0
(-4990 4505);
DISPLAY 0.787234 (-4990 4505);
FORCEPROP 2 LAST CDS_LIB pure_quanta
J 0
(-5000 4625);
PAINT MONO (-5000 4625);
DISPLAY INVISIBLE (-5000 4625);
FORCEPROP 1 LAST $LOCATION C249
J 0
(-4950 4825);
DISPLAY 1.021277 (-4950 4825);
DISPLAY INVISIBLE (-4950 4825);
FORCEPROP 2 LAST CDS_LOCATION C249
J 0
(-4950 4825);
DISPLAY 1.021277 (-4950 4825);
DISPLAY INVISIBLE (-4950 4825);
FORCEPROP 2 LAST $SEC 1
J 0
(-4950 4825);
DISPLAY 0.680851 (-4950 4825);
PAINT MONO (-4950 4825);
DISPLAY INVISIBLE (-4950 4825);
FORCEPROP 2 LAST CDS_SEC 1
J 0
(-4950 4825);
DISPLAY 1.021277 (-4950 4825);
DISPLAY INVISIBLE (-4950 4825);
FORCEPROP 1 LAST PATH I46
J 0
(-4950 4775);
DISPLAY 0.978723 (-4950 4775);
PAINT WHITE (-4950 4775);
DISPLAY INVISIBLE (-4950 4775);
FORCEADD Q_CAP..1
(-4550 3050);
FORCEPROP 1 LAST PART_NUMBER CH622KMEB01
J 0
(-4500 2900);
DISPLAY 0.638298 (-4500 2900);
DISPLAY INVISIBLE (-4500 2900);
FORCEPROP 1 LAST TOLERANCE 20%
J 0
(-4500 3000);
DISPLAY 0.638298 (-4500 3000);
FORCEPROP 1 LAST VALUE 22UF
J 0
(-4500 3100);
DISPLAY 0.638298 (-4500 3100);
FORCEPROP 1 LAST VOLTAGE 4V
J 0
(-4500 3050);
DISPLAY 0.638298 (-4500 3050);
FORCEPROP 1 LAST MATERIAL X6S
J 0
(-4500 2950);
DISPLAY 0.638298 (-4500 2950);
FORCEPROP 1 LAST PACK_TYPE C0402
J 0
(-4500 2850);
DISPLAY 0.638298 (-4500 2850);
FORCEPROP 1 LAST $LOCATION C434
J 0
(-4500 3150);
DISPLAY 0.978723 (-4500 3150);
FORCEPROP 1 LASTPIN (-4550 3150) $PN 1
J 0
(-4540 3130);
DISPLAY 0.787234 (-4540 3130);
FORCEPROP 1 LASTPIN (-4550 2950) $PN 2
J 0
(-4540 2930);
DISPLAY 0.787234 (-4540 2930);
FORCEPROP 2 LAST CDS_LIB pure_quanta
J 0
(-4550 3050);
PAINT MONO (-4550 3050);
DISPLAY INVISIBLE (-4550 3050);
FORCEPROP 2 LAST CDS_LOCATION C434
J 0
(-4500 3250);
DISPLAY 1.021277 (-4500 3250);
DISPLAY INVISIBLE (-4500 3250);
FORCEPROP 2 LAST $SEC 1
J 0
(-4500 3250);
DISPLAY 0.680851 (-4500 3250);
PAINT MONO (-4500 3250);
DISPLAY INVISIBLE (-4500 3250);
FORCEPROP 2 LAST CDS_SEC 1
J 0
(-4500 3250);
DISPLAY 1.021277 (-4500 3250);
DISPLAY INVISIBLE (-4500 3250);
FORCEPROP 1 LAST PATH I47
J 0
(-4500 3200);
DISPLAY 0.978723 (-4500 3200);
PAINT WHITE (-4500 3200);
DISPLAY INVISIBLE (-4500 3200);
FORCEADD Q_CAP..1
(-4550 3850);
FORCEPROP 1 LAST PART_NUMBER CH647KMEA04
J 0
(-4500 3700);
DISPLAY 0.638298 (-4500 3700);
DISPLAY INVISIBLE (-4500 3700);
FORCEPROP 1 LAST TOLERANCE 20%
J 0
(-4500 3800);
DISPLAY 0.638298 (-4500 3800);
FORCEPROP 1 LAST VOLTAGE 4V
J 0
(-4500 3850);
DISPLAY 0.638298 (-4500 3850);
FORCEPROP 1 LAST PACK_TYPE C0805
J 0
(-4500 3650);
DISPLAY 0.638298 (-4500 3650);
FORCEPROP 1 LAST VALUE 47UF
J 0
(-4500 3900);
DISPLAY 0.638298 (-4500 3900);
FORCEPROP 1 LAST MATERIAL X6S
J 0
(-4500 3750);
DISPLAY 0.638298 (-4500 3750);
FORCEPROP 1 LAST $LOCATION C255
J 0
(-4500 3950);
DISPLAY 0.638298 (-4500 3950);
FORCEPROP 1 LASTPIN (-4550 3950) $PN 1
J 0
(-4540 3930);
DISPLAY 0.787234 (-4540 3930);
FORCEPROP 1 LASTPIN (-4550 3750) $PN 2
J 0
(-4540 3730);
DISPLAY 0.787234 (-4540 3730);
FORCEPROP 2 LAST CDS_LIB pure_quanta
J 0
(-4550 3850);
PAINT MONO (-4550 3850);
DISPLAY INVISIBLE (-4550 3850);
FORCEPROP 1 LAST $LOCATION C255
J 0
(-4500 4050);
DISPLAY 1.021277 (-4500 4050);
DISPLAY INVISIBLE (-4500 4050);
FORCEPROP 2 LAST CDS_LOCATION C255
J 0
(-4500 4050);
DISPLAY 1.021277 (-4500 4050);
DISPLAY INVISIBLE (-4500 4050);
FORCEPROP 2 LAST $SEC 1
J 0
(-4500 4050);
DISPLAY 0.680851 (-4500 4050);
PAINT MONO (-4500 4050);
DISPLAY INVISIBLE (-4500 4050);
FORCEPROP 2 LAST CDS_SEC 1
J 0
(-4500 4050);
DISPLAY 1.021277 (-4500 4050);
DISPLAY INVISIBLE (-4500 4050);
FORCEPROP 1 LAST PATH I48
J 0
(-4500 4000);
DISPLAY 0.978723 (-4500 4000);
PAINT WHITE (-4500 4000);
DISPLAY INVISIBLE (-4500 4000);
FORCEADD Q_CAP..1
(-4100 3050);
FORCEPROP 1 LAST PART_NUMBER CH622KMEB01
J 0
(-4050 2900);
DISPLAY 0.638298 (-4050 2900);
DISPLAY INVISIBLE (-4050 2900);
FORCEPROP 1 LAST VOLTAGE 4V
J 0
(-4050 3050);
DISPLAY 0.638298 (-4050 3050);
FORCEPROP 1 LAST VALUE 22UF
J 0
(-4050 3100);
DISPLAY 0.638298 (-4050 3100);
FORCEPROP 1 LAST TOLERANCE 20%
J 0
(-4050 3000);
DISPLAY 0.638298 (-4050 3000);
FORCEPROP 1 LAST PACK_TYPE C0402
J 0
(-4050 2850);
DISPLAY 0.638298 (-4050 2850);
FORCEPROP 1 LAST MATERIAL X6S
J 0
(-4050 2950);
DISPLAY 0.638298 (-4050 2950);
FORCEPROP 1 LAST $LOCATION C436
J 0
(-4050 3150);
DISPLAY 0.978723 (-4050 3150);
FORCEPROP 1 LASTPIN (-4100 3150) $PN 1
J 0
(-4090 3130);
DISPLAY 0.787234 (-4090 3130);
FORCEPROP 1 LASTPIN (-4100 2950) $PN 2
J 0
(-4090 2930);
DISPLAY 0.787234 (-4090 2930);
FORCEPROP 2 LAST CDS_LIB pure_quanta
J 0
(-4100 3050);
PAINT MONO (-4100 3050);
DISPLAY INVISIBLE (-4100 3050);
FORCEPROP 2 LAST CDS_LOCATION C436
J 0
(-4050 3250);
DISPLAY 1.021277 (-4050 3250);
DISPLAY INVISIBLE (-4050 3250);
FORCEPROP 2 LAST $SEC 1
J 0
(-4050 3250);
DISPLAY 0.680851 (-4050 3250);
PAINT MONO (-4050 3250);
DISPLAY INVISIBLE (-4050 3250);
FORCEPROP 2 LAST CDS_SEC 1
J 0
(-4050 3250);
DISPLAY 1.021277 (-4050 3250);
DISPLAY INVISIBLE (-4050 3250);
FORCEPROP 1 LAST PATH I49
J 0
(-4050 3200);
DISPLAY 0.978723 (-4050 3200);
PAINT WHITE (-4050 3200);
DISPLAY INVISIBLE (-4050 3200);
FORCEADD Q_CAP..1
(-5900 2225);
FORCEPROP 1 LAST PART_NUMBER CH622KMEB01
J 0
(-5850 2075);
DISPLAY 0.638298 (-5850 2075);
DISPLAY INVISIBLE (-5850 2075);
FORCEPROP 1 LAST TOLERANCE 20%
J 0
(-5850 2175);
DISPLAY 0.638298 (-5850 2175);
FORCEPROP 1 LAST VOLTAGE 4V
J 0
(-5850 2225);
DISPLAY 0.638298 (-5850 2225);
FORCEPROP 1 LAST MATERIAL X6S
J 0
(-5850 2125);
DISPLAY 0.638298 (-5850 2125);
FORCEPROP 1 LAST PACK_TYPE C0402
J 0
(-5850 2025);
DISPLAY 0.638298 (-5850 2025);
FORCEPROP 1 LAST VALUE 22UF
J 0
(-5850 2275);
DISPLAY 0.638298 (-5850 2275);
FORCEPROP 1 LAST $LOCATION C430
J 0
(-5850 2325);
DISPLAY 0.978723 (-5850 2325);
FORCEPROP 1 LASTPIN (-5900 2325) $PN 1
J 0
(-5890 2305);
DISPLAY 0.787234 (-5890 2305);
FORCEPROP 1 LASTPIN (-5900 2125) $PN 2
J 0
(-5890 2105);
DISPLAY 0.787234 (-5890 2105);
FORCEPROP 2 LAST CDS_LIB pure_quanta
J 0
(-5900 2225);
PAINT MONO (-5900 2225);
DISPLAY INVISIBLE (-5900 2225);
FORCEPROP 2 LAST CDS_LOCATION C430
J 0
(-5850 2425);
DISPLAY 1.021277 (-5850 2425);
DISPLAY INVISIBLE (-5850 2425);
FORCEPROP 2 LAST $SEC 1
J 0
(-5850 2425);
DISPLAY 0.680851 (-5850 2425);
PAINT MONO (-5850 2425);
DISPLAY INVISIBLE (-5850 2425);
FORCEPROP 2 LAST CDS_SEC 1
J 0
(-5850 2425);
DISPLAY 1.021277 (-5850 2425);
DISPLAY INVISIBLE (-5850 2425);
FORCEPROP 1 LAST PATH I5
J 0
(-5850 2375);
DISPLAY 0.978723 (-5850 2375);
PAINT WHITE (-5850 2375);
DISPLAY INVISIBLE (-5850 2375);
FORCEADD Q_CAP..1
(-4100 3850);
FORCEPROP 1 LAST PART_NUMBER CH647KMEA04
J 0
(-4050 3700);
DISPLAY 0.638298 (-4050 3700);
DISPLAY INVISIBLE (-4050 3700);
FORCEPROP 1 LAST VOLTAGE 4V
J 0
(-4050 3850);
DISPLAY 0.638298 (-4050 3850);
FORCEPROP 1 LAST TOLERANCE 20%
J 0
(-4050 3800);
DISPLAY 0.638298 (-4050 3800);
FORCEPROP 1 LAST PACK_TYPE C0805
J 0
(-4050 3650);
DISPLAY 0.638298 (-4050 3650);
FORCEPROP 1 LAST VALUE 47UF
J 0
(-4050 3900);
DISPLAY 0.638298 (-4050 3900);
FORCEPROP 1 LAST MATERIAL X6S
J 0
(-4050 3750);
DISPLAY 0.638298 (-4050 3750);
FORCEPROP 1 LAST $LOCATION C260
J 0
(-4050 3950);
DISPLAY 0.638298 (-4050 3950);
FORCEPROP 1 LASTPIN (-4100 3950) $PN 1
J 0
(-4090 3930);
DISPLAY 0.787234 (-4090 3930);
FORCEPROP 1 LASTPIN (-4100 3750) $PN 2
J 0
(-4090 3730);
DISPLAY 0.787234 (-4090 3730);
FORCEPROP 2 LAST CDS_LIB pure_quanta
J 0
(-4100 3850);
PAINT MONO (-4100 3850);
DISPLAY INVISIBLE (-4100 3850);
FORCEPROP 1 LAST $LOCATION C260
J 0
(-4050 4050);
DISPLAY 1.021277 (-4050 4050);
DISPLAY INVISIBLE (-4050 4050);
FORCEPROP 2 LAST CDS_LOCATION C260
J 0
(-4050 4050);
DISPLAY 1.021277 (-4050 4050);
DISPLAY INVISIBLE (-4050 4050);
FORCEPROP 2 LAST $SEC 1
J 0
(-4050 4050);
DISPLAY 0.680851 (-4050 4050);
PAINT MONO (-4050 4050);
DISPLAY INVISIBLE (-4050 4050);
FORCEPROP 2 LAST CDS_SEC 1
J 0
(-4050 4050);
DISPLAY 1.021277 (-4050 4050);
DISPLAY INVISIBLE (-4050 4050);
FORCEPROP 1 LAST PATH I50
J 0
(-4050 4000);
DISPLAY 0.978723 (-4050 4000);
PAINT WHITE (-4050 4000);
DISPLAY INVISIBLE (-4050 4000);
FORCEADD Q_CAP..1
(-4550 4625);
FORCEPROP 1 LAST PART_NUMBER CH6101MEB03
J 0
(-4500 4475);
DISPLAY 0.638298 (-4500 4475);
DISPLAY INVISIBLE (-4500 4475);
FORCEPROP 1 LAST VALUE 10UF
J 0
(-4500 4675);
DISPLAY 0.638298 (-4500 4675);
FORCEPROP 1 LAST VOLTAGE 6.3V
J 0
(-4500 4625);
DISPLAY 0.638298 (-4500 4625);
FORCEPROP 1 LAST MATERIAL X6S
J 0
(-4500 4525);
DISPLAY 0.638298 (-4500 4525);
FORCEPROP 1 LAST TOLERANCE 20%
J 0
(-4500 4575);
DISPLAY 0.638298 (-4500 4575);
FORCEPROP 1 LAST PACK_TYPE C0402
J 0
(-4500 4425);
DISPLAY 0.638298 (-4500 4425);
FORCEPROP 1 LAST $LOCATION C254
J 0
(-4500 4725);
DISPLAY 0.638298 (-4500 4725);
FORCEPROP 1 LASTPIN (-4550 4725) $PN 1
J 0
(-4540 4705);
DISPLAY 0.787234 (-4540 4705);
FORCEPROP 1 LASTPIN (-4550 4525) $PN 2
J 0
(-4540 4505);
DISPLAY 0.787234 (-4540 4505);
FORCEPROP 2 LAST CDS_LIB pure_quanta
J 0
(-4550 4625);
PAINT MONO (-4550 4625);
DISPLAY INVISIBLE (-4550 4625);
FORCEPROP 1 LAST $LOCATION C254
J 0
(-4500 4825);
DISPLAY 1.021277 (-4500 4825);
DISPLAY INVISIBLE (-4500 4825);
FORCEPROP 2 LAST CDS_LOCATION C254
J 0
(-4500 4825);
DISPLAY 1.021277 (-4500 4825);
DISPLAY INVISIBLE (-4500 4825);
FORCEPROP 2 LAST $SEC 1
J 0
(-4500 4825);
DISPLAY 0.680851 (-4500 4825);
PAINT MONO (-4500 4825);
DISPLAY INVISIBLE (-4500 4825);
FORCEPROP 2 LAST CDS_SEC 1
J 0
(-4500 4825);
DISPLAY 1.021277 (-4500 4825);
DISPLAY INVISIBLE (-4500 4825);
FORCEPROP 1 LAST PATH I51
J 0
(-4500 4775);
DISPLAY 0.978723 (-4500 4775);
PAINT WHITE (-4500 4775);
DISPLAY INVISIBLE (-4500 4775);
FORCEADD Q_CAP..1
(-4100 4625);
FORCEPROP 1 LAST PART_NUMBER CH6101MEB03
J 0
(-4050 4475);
DISPLAY 0.638298 (-4050 4475);
DISPLAY INVISIBLE (-4050 4475);
FORCEPROP 1 LAST VOLTAGE 6.3V
J 0
(-4050 4625);
DISPLAY 0.638298 (-4050 4625);
FORCEPROP 1 LAST VALUE 10UF
J 0
(-4050 4675);
DISPLAY 0.638298 (-4050 4675);
FORCEPROP 1 LAST TOLERANCE 20%
J 0
(-4050 4575);
DISPLAY 0.638298 (-4050 4575);
FORCEPROP 1 LAST MATERIAL X6S
J 0
(-4050 4525);
DISPLAY 0.638298 (-4050 4525);
FORCEPROP 1 LAST PACK_TYPE C0402
J 0
(-4050 4425);
DISPLAY 0.638298 (-4050 4425);
FORCEPROP 1 LAST $LOCATION C259
J 0
(-4050 4725);
DISPLAY 0.638298 (-4050 4725);
FORCEPROP 1 LASTPIN (-4100 4725) $PN 1
J 0
(-4090 4705);
DISPLAY 0.787234 (-4090 4705);
FORCEPROP 1 LASTPIN (-4100 4525) $PN 2
J 0
(-4090 4505);
DISPLAY 0.787234 (-4090 4505);
FORCEPROP 2 LAST CDS_LIB pure_quanta
J 0
(-4100 4625);
PAINT MONO (-4100 4625);
DISPLAY INVISIBLE (-4100 4625);
FORCEPROP 1 LAST $LOCATION C259
J 0
(-4050 4825);
DISPLAY 1.021277 (-4050 4825);
DISPLAY INVISIBLE (-4050 4825);
FORCEPROP 2 LAST CDS_LOCATION C259
J 0
(-4050 4825);
DISPLAY 1.021277 (-4050 4825);
DISPLAY INVISIBLE (-4050 4825);
FORCEPROP 2 LAST $SEC 1
J 0
(-4050 4825);
DISPLAY 0.680851 (-4050 4825);
PAINT MONO (-4050 4825);
DISPLAY INVISIBLE (-4050 4825);
FORCEPROP 2 LAST CDS_SEC 1
J 0
(-4050 4825);
DISPLAY 1.021277 (-4050 4825);
DISPLAY INVISIBLE (-4050 4825);
FORCEPROP 1 LAST PATH I52
J 0
(-4050 4775);
DISPLAY 0.978723 (-4050 4775);
PAINT WHITE (-4050 4775);
DISPLAY INVISIBLE (-4050 4775);
FORCEADD Q_CAP..1
(-3650 2225);
FORCEPROP 1 LAST PART_NUMBER CH622KMEB01
J 0
(-3600 2075);
DISPLAY 0.638298 (-3600 2075);
DISPLAY INVISIBLE (-3600 2075);
FORCEPROP 1 LAST PACK_TYPE C0402
J 0
(-3600 2025);
DISPLAY 0.638298 (-3600 2025);
FORCEPROP 1 LAST VOLTAGE 4V
J 0
(-3600 2225);
DISPLAY 0.638298 (-3600 2225);
FORCEPROP 1 LAST TOLERANCE 20%
J 0
(-3600 2175);
DISPLAY 0.638298 (-3600 2175);
FORCEPROP 1 LAST VALUE 22UF
J 0
(-3600 2275);
DISPLAY 0.638298 (-3600 2275);
FORCEPROP 1 LAST MATERIAL X6S
J 0
(-3600 2125);
DISPLAY 0.638298 (-3600 2125);
FORCEPROP 1 LAST $LOCATION C439
J 0
(-3600 2325);
DISPLAY 0.978723 (-3600 2325);
FORCEPROP 1 LASTPIN (-3650 2325) $PN 1
J 0
(-3640 2305);
DISPLAY 0.787234 (-3640 2305);
FORCEPROP 1 LASTPIN (-3650 2125) $PN 2
J 0
(-3640 2105);
DISPLAY 0.787234 (-3640 2105);
FORCEPROP 2 LAST CDS_LIB pure_quanta
J 0
(-3650 2225);
PAINT MONO (-3650 2225);
DISPLAY INVISIBLE (-3650 2225);
FORCEPROP 2 LAST CDS_LOCATION C439
J 0
(-3600 2425);
DISPLAY 1.021277 (-3600 2425);
DISPLAY INVISIBLE (-3600 2425);
FORCEPROP 2 LAST $SEC 1
J 0
(-3600 2425);
DISPLAY 0.680851 (-3600 2425);
PAINT MONO (-3600 2425);
DISPLAY INVISIBLE (-3600 2425);
FORCEPROP 2 LAST CDS_SEC 1
J 0
(-3600 2425);
DISPLAY 1.021277 (-3600 2425);
DISPLAY INVISIBLE (-3600 2425);
FORCEPROP 1 LAST PATH I53
J 0
(-3600 2375);
DISPLAY 0.978723 (-3600 2375);
PAINT WHITE (-3600 2375);
DISPLAY INVISIBLE (-3600 2375);
FORCEADD UNIVERSAL_GND..1
(-3200 2700);
FORCEPROP 3 LASTPIN (-3200 2750) SIG_NAME GND\g
J 0
(-3190 2760);
DISPLAY 0.659574 (-3190 2760);
PAINT MONO (-3190 2760);
DISPLAY INVISIBLE (-3190 2760);
FORCEPROP 2 LAST CDS_LIB logical_power
J 0
(-3200 2700);
PAINT MONO (-3200 2700);
DISPLAY INVISIBLE (-3200 2700);
FORCEPROP 1 LAST HDL_POWER GND
J 1
(-3175 2625);
DISPLAY 0.872340 (-3175 2625);
PAINT GREEN (-3175 2625);
DISPLAY INVISIBLE (-3175 2625);
FORCEPROP 1 LAST PATH I54
J 0
(-3125 2700);
DISPLAY 0.872340 (-3125 2700);
PAINT AQUA (-3125 2700);
DISPLAY INVISIBLE (-3125 2700);
FORCEADD Q_CAP..1
(-3200 2225);
FORCEPROP 1 LAST PART_NUMBER CH622KMEB01
J 0
(-3150 2075);
DISPLAY 0.638298 (-3150 2075);
DISPLAY INVISIBLE (-3150 2075);
FORCEPROP 1 LAST TOLERANCE 20%
J 0
(-3150 2175);
DISPLAY 0.638298 (-3150 2175);
FORCEPROP 1 LAST VOLTAGE 4V
J 0
(-3150 2225);
DISPLAY 0.638298 (-3150 2225);
FORCEPROP 1 LAST PACK_TYPE C0402
J 0
(-3150 2025);
DISPLAY 0.638298 (-3150 2025);
FORCEPROP 1 LAST VALUE 22UF
J 0
(-3150 2275);
DISPLAY 0.638298 (-3150 2275);
FORCEPROP 1 LAST MATERIAL X6S
J 0
(-3150 2125);
DISPLAY 0.638298 (-3150 2125);
FORCEPROP 1 LAST $LOCATION C441
J 0
(-3150 2325);
DISPLAY 0.978723 (-3150 2325);
FORCEPROP 1 LASTPIN (-3200 2325) $PN 1
J 0
(-3190 2305);
DISPLAY 0.787234 (-3190 2305);
FORCEPROP 1 LASTPIN (-3200 2125) $PN 2
J 0
(-3190 2105);
DISPLAY 0.787234 (-3190 2105);
FORCEPROP 2 LAST CDS_LIB pure_quanta
J 0
(-3200 2225);
PAINT MONO (-3200 2225);
DISPLAY INVISIBLE (-3200 2225);
FORCEPROP 2 LAST CDS_LOCATION C441
J 0
(-3150 2425);
DISPLAY 1.021277 (-3150 2425);
DISPLAY INVISIBLE (-3150 2425);
FORCEPROP 2 LAST $SEC 1
J 0
(-3150 2425);
DISPLAY 0.680851 (-3150 2425);
PAINT MONO (-3150 2425);
DISPLAY INVISIBLE (-3150 2425);
FORCEPROP 2 LAST CDS_SEC 1
J 0
(-3150 2425);
DISPLAY 1.021277 (-3150 2425);
DISPLAY INVISIBLE (-3150 2425);
FORCEPROP 1 LAST PATH I55
J 0
(-3150 2375);
DISPLAY 0.978723 (-3150 2375);
PAINT WHITE (-3150 2375);
DISPLAY INVISIBLE (-3150 2375);
FORCEADD UNIVERSAL_GND..1
(-2750 1875);
FORCEPROP 3 LASTPIN (-2750 1925) SIG_NAME GND\g
J 0
(-2740 1935);
DISPLAY 0.659574 (-2740 1935);
PAINT MONO (-2740 1935);
DISPLAY INVISIBLE (-2740 1935);
FORCEPROP 2 LAST CDS_LIB logical_power
J 0
(-2750 1875);
PAINT MONO (-2750 1875);
DISPLAY INVISIBLE (-2750 1875);
FORCEPROP 1 LAST HDL_POWER GND
J 1
(-2725 1800);
DISPLAY 0.872340 (-2725 1800);
PAINT GREEN (-2725 1800);
DISPLAY INVISIBLE (-2725 1800);
FORCEPROP 1 LAST PATH I56
J 0
(-2675 1875);
DISPLAY 0.872340 (-2675 1875);
PAINT AQUA (-2675 1875);
DISPLAY INVISIBLE (-2675 1875);
FORCEADD Q_CAP..1
(-2750 2225);
FORCEPROP 1 LAST PART_NUMBER CH622KMEB01
J 0
(-2700 2075);
DISPLAY 0.638298 (-2700 2075);
DISPLAY INVISIBLE (-2700 2075);
FORCEPROP 1 LAST VOLTAGE 4V
J 0
(-2700 2225);
DISPLAY 0.638298 (-2700 2225);
FORCEPROP 1 LAST TOLERANCE 20%
J 0
(-2700 2175);
DISPLAY 0.638298 (-2700 2175);
FORCEPROP 1 LAST MATERIAL X6S
J 0
(-2700 2125);
DISPLAY 0.638298 (-2700 2125);
FORCEPROP 1 LAST PACK_TYPE C0402
J 0
(-2700 2025);
DISPLAY 0.638298 (-2700 2025);
FORCEPROP 1 LAST VALUE 22UF
J 0
(-2700 2275);
DISPLAY 0.638298 (-2700 2275);
FORCEPROP 1 LAST $LOCATION C442
J 0
(-2700 2325);
DISPLAY 0.978723 (-2700 2325);
FORCEPROP 1 LASTPIN (-2750 2325) $PN 1
J 0
(-2740 2305);
DISPLAY 0.787234 (-2740 2305);
FORCEPROP 1 LASTPIN (-2750 2125) $PN 2
J 0
(-2740 2105);
DISPLAY 0.787234 (-2740 2105);
FORCEPROP 2 LAST CDS_LIB pure_quanta
J 0
(-2750 2225);
PAINT MONO (-2750 2225);
DISPLAY INVISIBLE (-2750 2225);
FORCEPROP 2 LAST CDS_LOCATION C442
J 0
(-2700 2425);
DISPLAY 1.021277 (-2700 2425);
DISPLAY INVISIBLE (-2700 2425);
FORCEPROP 2 LAST $SEC 1
J 0
(-2700 2425);
DISPLAY 0.680851 (-2700 2425);
PAINT MONO (-2700 2425);
DISPLAY INVISIBLE (-2700 2425);
FORCEPROP 2 LAST CDS_SEC 1
J 0
(-2700 2425);
DISPLAY 1.021277 (-2700 2425);
DISPLAY INVISIBLE (-2700 2425);
FORCEPROP 1 LAST PATH I57
J 0
(-2700 2375);
DISPLAY 0.978723 (-2700 2375);
PAINT WHITE (-2700 2375);
DISPLAY INVISIBLE (-2700 2375);
FORCEADD Q_CAP..1
(-3650 3050);
FORCEPROP 1 LAST PART_NUMBER CH622KMEB01
J 0
(-3600 2900);
DISPLAY 0.638298 (-3600 2900);
DISPLAY INVISIBLE (-3600 2900);
FORCEPROP 1 LAST TOLERANCE 20%
J 0
(-3600 3000);
DISPLAY 0.638298 (-3600 3000);
FORCEPROP 1 LAST VOLTAGE 4V
J 0
(-3600 3050);
DISPLAY 0.638298 (-3600 3050);
FORCEPROP 1 LAST VALUE 22UF
J 0
(-3600 3100);
DISPLAY 0.638298 (-3600 3100);
FORCEPROP 1 LAST MATERIAL X6S
J 0
(-3600 2950);
DISPLAY 0.638298 (-3600 2950);
FORCEPROP 1 LAST PACK_TYPE C0402
J 0
(-3600 2850);
DISPLAY 0.638298 (-3600 2850);
FORCEPROP 1 LAST $LOCATION C438
J 0
(-3600 3150);
DISPLAY 0.978723 (-3600 3150);
FORCEPROP 1 LASTPIN (-3650 3150) $PN 1
J 0
(-3640 3130);
DISPLAY 0.787234 (-3640 3130);
FORCEPROP 1 LASTPIN (-3650 2950) $PN 2
J 0
(-3640 2930);
DISPLAY 0.787234 (-3640 2930);
FORCEPROP 2 LAST CDS_LIB pure_quanta
J 0
(-3650 3050);
PAINT MONO (-3650 3050);
DISPLAY INVISIBLE (-3650 3050);
FORCEPROP 2 LAST CDS_LOCATION C438
J 0
(-3600 3250);
DISPLAY 1.021277 (-3600 3250);
DISPLAY INVISIBLE (-3600 3250);
FORCEPROP 2 LAST $SEC 1
J 0
(-3600 3250);
DISPLAY 0.680851 (-3600 3250);
PAINT MONO (-3600 3250);
DISPLAY INVISIBLE (-3600 3250);
FORCEPROP 2 LAST CDS_SEC 1
J 0
(-3600 3250);
DISPLAY 1.021277 (-3600 3250);
DISPLAY INVISIBLE (-3600 3250);
FORCEPROP 1 LAST PATH I58
J 0
(-3600 3200);
DISPLAY 0.978723 (-3600 3200);
PAINT WHITE (-3600 3200);
DISPLAY INVISIBLE (-3600 3200);
FORCEADD Q_CAP..1
(-3650 3850);
FORCEPROP 1 LAST PART_NUMBER CH647KMEA04
J 0
(-3600 3700);
DISPLAY 0.638298 (-3600 3700);
DISPLAY INVISIBLE (-3600 3700);
FORCEPROP 1 LAST VOLTAGE 4V
J 0
(-3600 3850);
DISPLAY 0.638298 (-3600 3850);
FORCEPROP 1 LAST TOLERANCE 20%
J 0
(-3600 3800);
DISPLAY 0.638298 (-3600 3800);
FORCEPROP 1 LAST PACK_TYPE C0805
J 0
(-3600 3650);
DISPLAY 0.638298 (-3600 3650);
FORCEPROP 1 LAST VALUE 47UF
J 0
(-3600 3900);
DISPLAY 0.638298 (-3600 3900);
FORCEPROP 1 LAST MATERIAL X6S
J 0
(-3600 3750);
DISPLAY 0.638298 (-3600 3750);
FORCEPROP 1 LAST $LOCATION C265
J 0
(-3600 3950);
DISPLAY 0.638298 (-3600 3950);
FORCEPROP 1 LASTPIN (-3650 3950) $PN 1
J 0
(-3640 3930);
DISPLAY 0.787234 (-3640 3930);
FORCEPROP 1 LASTPIN (-3650 3750) $PN 2
J 0
(-3640 3730);
DISPLAY 0.787234 (-3640 3730);
FORCEPROP 2 LAST CDS_LIB pure_quanta
J 0
(-3650 3850);
PAINT MONO (-3650 3850);
DISPLAY INVISIBLE (-3650 3850);
FORCEPROP 1 LAST $LOCATION C265
J 0
(-3600 4050);
DISPLAY 1.021277 (-3600 4050);
DISPLAY INVISIBLE (-3600 4050);
FORCEPROP 2 LAST CDS_LOCATION C265
J 0
(-3600 4050);
DISPLAY 1.021277 (-3600 4050);
DISPLAY INVISIBLE (-3600 4050);
FORCEPROP 2 LAST $SEC 1
J 0
(-3600 4050);
DISPLAY 0.680851 (-3600 4050);
PAINT MONO (-3600 4050);
DISPLAY INVISIBLE (-3600 4050);
FORCEPROP 2 LAST CDS_SEC 1
J 0
(-3600 4050);
DISPLAY 1.021277 (-3600 4050);
DISPLAY INVISIBLE (-3600 4050);
FORCEPROP 1 LAST PATH I59
J 0
(-3600 4000);
DISPLAY 0.978723 (-3600 4000);
PAINT WHITE (-3600 4000);
DISPLAY INVISIBLE (-3600 4000);
FORCEADD UNIVERSAL_GND..1
(-5900 2725);
FORCEPROP 3 LASTPIN (-5900 2775) SIG_NAME GND\g
J 0
(-5890 2785);
DISPLAY 0.659574 (-5890 2785);
PAINT MONO (-5890 2785);
DISPLAY INVISIBLE (-5890 2785);
FORCEPROP 2 LAST CDS_LIB logical_power
J 0
(-5900 2725);
PAINT MONO (-5900 2725);
DISPLAY INVISIBLE (-5900 2725);
FORCEPROP 1 LAST HDL_POWER GND
J 1
(-5875 2650);
DISPLAY 0.872340 (-5875 2650);
PAINT GREEN (-5875 2650);
DISPLAY INVISIBLE (-5875 2650);
FORCEPROP 1 LAST PATH I6
J 0
(-5825 2725);
DISPLAY 0.872340 (-5825 2725);
PAINT AQUA (-5825 2725);
DISPLAY INVISIBLE (-5825 2725);
FORCEADD UNIVERSAL_GND..1
(-3200 3500);
FORCEPROP 3 LASTPIN (-3200 3550) SIG_NAME GND\g
J 0
(-3190 3560);
DISPLAY 0.659574 (-3190 3560);
PAINT MONO (-3190 3560);
DISPLAY INVISIBLE (-3190 3560);
FORCEPROP 2 LAST CDS_LIB logical_power
J 0
(-3200 3500);
PAINT MONO (-3200 3500);
DISPLAY INVISIBLE (-3200 3500);
FORCEPROP 1 LAST HDL_POWER GND
J 1
(-3175 3425);
DISPLAY 0.872340 (-3175 3425);
PAINT GREEN (-3175 3425);
DISPLAY INVISIBLE (-3175 3425);
FORCEPROP 1 LAST PATH I60
J 0
(-3125 3500);
DISPLAY 0.872340 (-3125 3500);
PAINT AQUA (-3125 3500);
DISPLAY INVISIBLE (-3125 3500);
FORCEADD Q_CAP..1
(-3200 3050);
FORCEPROP 1 LAST PART_NUMBER CH622KMEB01
J 0
(-3150 2900);
DISPLAY 0.638298 (-3150 2900);
DISPLAY INVISIBLE (-3150 2900);
FORCEPROP 1 LAST MATERIAL X6S
J 0
(-3150 2950);
DISPLAY 0.638298 (-3150 2950);
FORCEPROP 1 LAST TOLERANCE 20%
J 0
(-3150 3000);
DISPLAY 0.638298 (-3150 3000);
FORCEPROP 1 LAST VALUE 22UF
J 0
(-3150 3100);
DISPLAY 0.638298 (-3150 3100);
FORCEPROP 1 LAST VOLTAGE 4V
J 0
(-3150 3050);
DISPLAY 0.638298 (-3150 3050);
FORCEPROP 1 LAST PACK_TYPE C0402
J 0
(-3150 2850);
DISPLAY 0.638298 (-3150 2850);
FORCEPROP 1 LAST $LOCATION C440
J 0
(-3150 3150);
DISPLAY 0.978723 (-3150 3150);
FORCEPROP 1 LASTPIN (-3200 3150) $PN 1
J 0
(-3190 3130);
DISPLAY 0.787234 (-3190 3130);
FORCEPROP 1 LASTPIN (-3200 2950) $PN 2
J 0
(-3190 2930);
DISPLAY 0.787234 (-3190 2930);
FORCEPROP 2 LAST CDS_LIB pure_quanta
J 0
(-3200 3050);
PAINT MONO (-3200 3050);
DISPLAY INVISIBLE (-3200 3050);
FORCEPROP 2 LAST CDS_LOCATION C440
J 0
(-3150 3250);
DISPLAY 1.021277 (-3150 3250);
DISPLAY INVISIBLE (-3150 3250);
FORCEPROP 2 LAST $SEC 1
J 0
(-3150 3250);
DISPLAY 0.680851 (-3150 3250);
PAINT MONO (-3150 3250);
DISPLAY INVISIBLE (-3150 3250);
FORCEPROP 2 LAST CDS_SEC 1
J 0
(-3150 3250);
DISPLAY 1.021277 (-3150 3250);
DISPLAY INVISIBLE (-3150 3250);
FORCEPROP 1 LAST PATH I61
J 0
(-3150 3200);
DISPLAY 0.978723 (-3150 3200);
PAINT WHITE (-3150 3200);
DISPLAY INVISIBLE (-3150 3200);
FORCEADD Q_CAP..1
(-3200 3850);
FORCEPROP 1 LAST PART_NUMBER CH647KMEA04
J 0
(-3150 3700);
DISPLAY 0.638298 (-3150 3700);
DISPLAY INVISIBLE (-3150 3700);
FORCEPROP 1 LAST VOLTAGE 4V
J 0
(-3150 3850);
DISPLAY 0.638298 (-3150 3850);
FORCEPROP 1 LAST TOLERANCE 20%
J 0
(-3150 3800);
DISPLAY 0.638298 (-3150 3800);
FORCEPROP 1 LAST PACK_TYPE C0805
J 0
(-3150 3650);
DISPLAY 0.638298 (-3150 3650);
FORCEPROP 1 LAST MATERIAL X6S
J 0
(-3150 3750);
DISPLAY 0.638298 (-3150 3750);
FORCEPROP 1 LAST VALUE 47UF
J 0
(-3150 3900);
DISPLAY 0.638298 (-3150 3900);
FORCEPROP 1 LAST $LOCATION C270
J 0
(-3150 3950);
DISPLAY 0.638298 (-3150 3950);
FORCEPROP 1 LASTPIN (-3200 3950) $PN 1
J 0
(-3190 3930);
DISPLAY 0.787234 (-3190 3930);
FORCEPROP 1 LASTPIN (-3200 3750) $PN 2
J 0
(-3190 3730);
DISPLAY 0.787234 (-3190 3730);
FORCEPROP 2 LAST CDS_LIB pure_quanta
J 0
(-3200 3850);
PAINT MONO (-3200 3850);
DISPLAY INVISIBLE (-3200 3850);
FORCEPROP 1 LAST $LOCATION C270
J 0
(-3150 4050);
DISPLAY 1.021277 (-3150 4050);
DISPLAY INVISIBLE (-3150 4050);
FORCEPROP 2 LAST CDS_LOCATION C270
J 0
(-3150 4050);
DISPLAY 1.021277 (-3150 4050);
DISPLAY INVISIBLE (-3150 4050);
FORCEPROP 2 LAST $SEC 1
J 0
(-3150 4050);
DISPLAY 0.680851 (-3150 4050);
PAINT MONO (-3150 4050);
DISPLAY INVISIBLE (-3150 4050);
FORCEPROP 2 LAST CDS_SEC 1
J 0
(-3150 4050);
DISPLAY 1.021277 (-3150 4050);
DISPLAY INVISIBLE (-3150 4050);
FORCEPROP 1 LAST PATH I62
J 0
(-3150 4000);
DISPLAY 0.978723 (-3150 4000);
PAINT WHITE (-3150 4000);
DISPLAY INVISIBLE (-3150 4000);
FORCEADD Q_CAP..1
(-3650 4625);
FORCEPROP 1 LAST PART_NUMBER CH6101MEB03
J 0
(-3600 4475);
DISPLAY 0.638298 (-3600 4475);
DISPLAY INVISIBLE (-3600 4475);
FORCEPROP 1 LAST VOLTAGE 6.3V
J 0
(-3600 4625);
DISPLAY 0.638298 (-3600 4625);
FORCEPROP 1 LAST VALUE 10UF
J 0
(-3600 4675);
DISPLAY 0.638298 (-3600 4675);
FORCEPROP 1 LAST MATERIAL X6S
J 0
(-3600 4525);
DISPLAY 0.638298 (-3600 4525);
FORCEPROP 1 LAST TOLERANCE 20%
J 0
(-3600 4575);
DISPLAY 0.638298 (-3600 4575);
FORCEPROP 1 LAST PACK_TYPE C0402
J 0
(-3600 4425);
DISPLAY 0.638298 (-3600 4425);
FORCEPROP 1 LAST $LOCATION C264
J 0
(-3600 4725);
DISPLAY 0.638298 (-3600 4725);
FORCEPROP 1 LASTPIN (-3650 4725) $PN 1
J 0
(-3640 4705);
DISPLAY 0.787234 (-3640 4705);
FORCEPROP 1 LASTPIN (-3650 4525) $PN 2
J 0
(-3640 4505);
DISPLAY 0.787234 (-3640 4505);
FORCEPROP 2 LAST CDS_LIB pure_quanta
J 0
(-3650 4625);
PAINT MONO (-3650 4625);
DISPLAY INVISIBLE (-3650 4625);
FORCEPROP 1 LAST $LOCATION C264
J 0
(-3600 4825);
DISPLAY 1.021277 (-3600 4825);
DISPLAY INVISIBLE (-3600 4825);
FORCEPROP 2 LAST CDS_LOCATION C264
J 0
(-3600 4825);
DISPLAY 1.021277 (-3600 4825);
DISPLAY INVISIBLE (-3600 4825);
FORCEPROP 2 LAST $SEC 1
J 0
(-3600 4825);
DISPLAY 0.680851 (-3600 4825);
PAINT MONO (-3600 4825);
DISPLAY INVISIBLE (-3600 4825);
FORCEPROP 2 LAST CDS_SEC 1
J 0
(-3600 4825);
DISPLAY 1.021277 (-3600 4825);
DISPLAY INVISIBLE (-3600 4825);
FORCEPROP 1 LAST PATH I63
J 0
(-3600 4775);
DISPLAY 0.978723 (-3600 4775);
PAINT WHITE (-3600 4775);
DISPLAY INVISIBLE (-3600 4775);
FORCEADD Q_CAP..1
(-3200 4625);
FORCEPROP 1 LAST PART_NUMBER CH6101MEB03
J 0
(-3150 4475);
DISPLAY 0.638298 (-3150 4475);
DISPLAY INVISIBLE (-3150 4475);
FORCEPROP 1 LAST VOLTAGE 6.3V
J 0
(-3150 4625);
DISPLAY 0.638298 (-3150 4625);
FORCEPROP 1 LAST VALUE 10UF
J 0
(-3150 4675);
DISPLAY 0.638298 (-3150 4675);
FORCEPROP 1 LAST MATERIAL X6S
J 0
(-3150 4525);
DISPLAY 0.638298 (-3150 4525);
FORCEPROP 1 LAST TOLERANCE 20%
J 0
(-3150 4575);
DISPLAY 0.638298 (-3150 4575);
FORCEPROP 1 LAST PACK_TYPE C0402
J 0
(-3150 4425);
DISPLAY 0.638298 (-3150 4425);
FORCEPROP 1 LAST $LOCATION C269
J 0
(-3150 4725);
DISPLAY 0.638298 (-3150 4725);
FORCEPROP 1 LASTPIN (-3200 4725) $PN 1
J 0
(-3190 4705);
DISPLAY 0.787234 (-3190 4705);
FORCEPROP 1 LASTPIN (-3200 4525) $PN 2
J 0
(-3190 4505);
DISPLAY 0.787234 (-3190 4505);
FORCEPROP 2 LAST CDS_LIB pure_quanta
J 0
(-3200 4625);
PAINT MONO (-3200 4625);
DISPLAY INVISIBLE (-3200 4625);
FORCEPROP 1 LAST $LOCATION C269
J 0
(-3150 4825);
DISPLAY 1.021277 (-3150 4825);
DISPLAY INVISIBLE (-3150 4825);
FORCEPROP 2 LAST CDS_LOCATION C269
J 0
(-3150 4825);
DISPLAY 1.021277 (-3150 4825);
DISPLAY INVISIBLE (-3150 4825);
FORCEPROP 2 LAST $SEC 1
J 0
(-3150 4825);
DISPLAY 0.680851 (-3150 4825);
PAINT MONO (-3150 4825);
DISPLAY INVISIBLE (-3150 4825);
FORCEPROP 2 LAST CDS_SEC 1
J 0
(-3150 4825);
DISPLAY 1.021277 (-3150 4825);
DISPLAY INVISIBLE (-3150 4825);
FORCEPROP 1 LAST PATH I64
J 0
(-3150 4775);
DISPLAY 0.978723 (-3150 4775);
PAINT WHITE (-3150 4775);
DISPLAY INVISIBLE (-3150 4775);
FORCEADD UNIVERSAL_GND..1
(-3200 4275);
FORCEPROP 3 LASTPIN (-3200 4325) SIG_NAME GND\g
J 0
(-3190 4335);
DISPLAY 0.659574 (-3190 4335);
PAINT MONO (-3190 4335);
DISPLAY INVISIBLE (-3190 4335);
FORCEPROP 2 LAST CDS_LIB logical_power
J 0
(-3200 4275);
PAINT MONO (-3200 4275);
DISPLAY INVISIBLE (-3200 4275);
FORCEPROP 1 LAST HDL_POWER GND
J 1
(-3175 4200);
DISPLAY 0.872340 (-3175 4200);
PAINT GREEN (-3175 4200);
DISPLAY INVISIBLE (-3175 4200);
FORCEPROP 1 LAST PATH I65
J 0
(-3125 4275);
DISPLAY 0.872340 (-3125 4275);
PAINT AQUA (-3125 4275);
DISPLAY INVISIBLE (-3125 4275);
FORCEADD Q_CAP..1
(-2725 4625);
FORCEPROP 1 LAST PART_NUMBER CH622KMEB01
J 0
(-2675 4475);
DISPLAY 0.638298 (-2675 4475);
DISPLAY INVISIBLE (-2675 4475);
FORCEPROP 1 LAST VOLTAGE 4V
J 0
(-2675 4625);
DISPLAY 0.638298 (-2675 4625);
FORCEPROP 1 LAST TOLERANCE 20%
J 0
(-2675 4575);
DISPLAY 0.638298 (-2675 4575);
FORCEPROP 1 LAST PACK_TYPE C0402
J 0
(-2675 4425);
DISPLAY 0.638298 (-2675 4425);
FORCEPROP 1 LAST MATERIAL X6S
J 0
(-2675 4525);
DISPLAY 0.638298 (-2675 4525);
FORCEPROP 1 LAST VALUE 22UF
J 0
(-2675 4675);
DISPLAY 0.638298 (-2675 4675);
FORCEPROP 1 LAST $LOCATION C274
J 0
(-2675 4725);
DISPLAY 0.638298 (-2675 4725);
FORCEPROP 1 LASTPIN (-2725 4725) $PN 1
J 0
(-2715 4705);
DISPLAY 0.787234 (-2715 4705);
FORCEPROP 1 LASTPIN (-2725 4525) $PN 2
J 0
(-2715 4505);
DISPLAY 0.787234 (-2715 4505);
FORCEPROP 2 LAST CDS_LIB pure_quanta
J 0
(-2725 4625);
PAINT MONO (-2725 4625);
DISPLAY INVISIBLE (-2725 4625);
FORCEPROP 1 LAST $LOCATION C274
J 0
(-2675 4825);
DISPLAY 1.021277 (-2675 4825);
DISPLAY INVISIBLE (-2675 4825);
FORCEPROP 2 LAST CDS_LOCATION C274
J 0
(-2675 4825);
DISPLAY 1.021277 (-2675 4825);
DISPLAY INVISIBLE (-2675 4825);
FORCEPROP 2 LAST $SEC 1
J 0
(-2675 4825);
DISPLAY 0.680851 (-2675 4825);
PAINT MONO (-2675 4825);
DISPLAY INVISIBLE (-2675 4825);
FORCEPROP 2 LAST CDS_SEC 1
J 0
(-2675 4825);
DISPLAY 1.021277 (-2675 4825);
DISPLAY INVISIBLE (-2675 4825);
FORCEPROP 1 LAST PATH I66
J 0
(-2675 4775);
DISPLAY 0.978723 (-2675 4775);
PAINT WHITE (-2675 4775);
DISPLAY INVISIBLE (-2675 4775);
FORCEADD Q_CAP..1
(-1975 3050);
FORCEPROP 1 LAST PART_NUMBER CH622KMEB01
J 0
(-1925 2900);
DISPLAY 0.638298 (-1925 2900);
DISPLAY INVISIBLE (-1925 2900);
FORCEPROP 1 LAST VALUE 22UF
J 0
(-1925 3100);
DISPLAY 0.638298 (-1925 3100);
FORCEPROP 1 LAST VOLTAGE 4V
J 0
(-1925 3050);
DISPLAY 0.638298 (-1925 3050);
FORCEPROP 1 LAST TOLERANCE 20%
J 0
(-1925 3000);
DISPLAY 0.638298 (-1925 3000);
FORCEPROP 1 LAST PACK_TYPE C0402
J 0
(-1925 2850);
DISPLAY 0.638298 (-1925 2850);
FORCEPROP 1 LAST MATERIAL X6S
J 0
(-1925 2950);
DISPLAY 0.638298 (-1925 2950);
FORCEPROP 1 LAST $LOCATION C443
J 0
(-1925 3150);
DISPLAY 0.978723 (-1925 3150);
FORCEPROP 1 LASTPIN (-1975 3150) $PN 1
J 0
(-1965 3130);
DISPLAY 0.787234 (-1965 3130);
FORCEPROP 1 LASTPIN (-1975 2950) $PN 2
J 0
(-1965 2930);
DISPLAY 0.787234 (-1965 2930);
FORCEPROP 2 LAST CDS_LIB pure_quanta
J 0
(-1975 3050);
PAINT MONO (-1975 3050);
DISPLAY INVISIBLE (-1975 3050);
FORCEPROP 2 LAST CDS_LOCATION C443
J 0
(-1925 3250);
DISPLAY 1.021277 (-1925 3250);
DISPLAY INVISIBLE (-1925 3250);
FORCEPROP 2 LAST $SEC 1
J 0
(-1925 3250);
DISPLAY 0.680851 (-1925 3250);
PAINT MONO (-1925 3250);
DISPLAY INVISIBLE (-1925 3250);
FORCEPROP 2 LAST CDS_SEC 1
J 0
(-1925 3250);
DISPLAY 1.021277 (-1925 3250);
DISPLAY INVISIBLE (-1925 3250);
FORCEPROP 1 LAST PATH I67
J 0
(-1925 3200);
DISPLAY 0.978723 (-1925 3200);
PAINT WHITE (-1925 3200);
DISPLAY INVISIBLE (-1925 3200);
FORCEADD UNIVERSAL_POWER..1
(-1975 3325);
FORCEPROP 3 LASTPIN (-1975 3275) SIG_NAME PVCCFA_EHV_CPU1\g
J 0
(-1965 3285);
DISPLAY 0.659574 (-1965 3285);
PAINT MONO (-1965 3285);
DISPLAY INVISIBLE (-1965 3285);
FORCEPROP 1 LAST HDL_POWER PVCCFA_EHV_CPU1
J 1
(-1950 3375);
DISPLAY 1.085106 (-1950 3375);
PAINT GREEN (-1950 3375);
FORCEPROP 2 LAST CDS_LIB logical_power
J 0
(-1975 3325);
PAINT MONO (-1975 3325);
DISPLAY INVISIBLE (-1975 3325);
FORCEPROP 1 LAST PATH I68
J 0
(-1925 3350);
DISPLAY 0.872340 (-1925 3350);
PAINT AQUA (-1925 3350);
DISPLAY INVISIBLE (-1925 3350);
FORCEADD UNIVERSAL_GND..1
(-1975 3500);
FORCEPROP 3 LASTPIN (-1975 3550) SIG_NAME GND\g
J 0
(-1965 3560);
DISPLAY 0.659574 (-1965 3560);
PAINT MONO (-1965 3560);
DISPLAY INVISIBLE (-1965 3560);
FORCEPROP 2 LAST CDS_LIB logical_power
J 0
(-1975 3500);
DISPLAY INVISIBLE (-1975 3500);
FORCEPROP 1 LAST HDL_POWER GND
J 1
(-1950 3425);
DISPLAY 0.872340 (-1950 3425);
PAINT GREEN (-1950 3425);
DISPLAY INVISIBLE (-1950 3425);
FORCEPROP 1 LAST PATH I69
J 0
(-1900 3500);
DISPLAY 0.872340 (-1900 3500);
PAINT AQUA (-1900 3500);
DISPLAY INVISIBLE (-1900 3500);
FORCEADD Q_CAP..1
(-7250 3050);
FORCEPROP 1 LAST PART_NUMBER CH622KMEB01
J 0
(-7200 2900);
DISPLAY 0.638298 (-7200 2900);
DISPLAY INVISIBLE (-7200 2900);
FORCEPROP 1 LAST TOLERANCE 20%
J 0
(-7200 3000);
DISPLAY 0.638298 (-7200 3000);
FORCEPROP 1 LAST VOLTAGE 4V
J 0
(-7200 3050);
DISPLAY 0.638298 (-7200 3050);
FORCEPROP 1 LAST PACK_TYPE C0402
J 0
(-7200 2850);
DISPLAY 0.638298 (-7200 2850);
FORCEPROP 1 LAST MATERIAL X6S
J 0
(-7200 2950);
DISPLAY 0.638298 (-7200 2950);
FORCEPROP 1 LAST VALUE 22UF
J 0
(-7200 3100);
DISPLAY 0.638298 (-7200 3100);
FORCEPROP 1 LAST $LOCATION C423
J 0
(-7200 3150);
DISPLAY 0.978723 (-7200 3150);
FORCEPROP 1 LASTPIN (-7250 3150) $PN 1
J 0
(-7240 3130);
DISPLAY 0.787234 (-7240 3130);
FORCEPROP 1 LASTPIN (-7250 2950) $PN 2
J 0
(-7240 2930);
DISPLAY 0.787234 (-7240 2930);
FORCEPROP 2 LAST CDS_LIB pure_quanta
J 0
(-7250 3050);
PAINT MONO (-7250 3050);
DISPLAY INVISIBLE (-7250 3050);
FORCEPROP 2 LAST CDS_LOCATION C423
J 0
(-7200 3250);
DISPLAY 1.021277 (-7200 3250);
DISPLAY INVISIBLE (-7200 3250);
FORCEPROP 2 LAST $SEC 1
J 0
(-7200 3250);
DISPLAY 0.680851 (-7200 3250);
PAINT MONO (-7200 3250);
DISPLAY INVISIBLE (-7200 3250);
FORCEPROP 2 LAST CDS_SEC 1
J 0
(-7200 3250);
DISPLAY 1.021277 (-7200 3250);
DISPLAY INVISIBLE (-7200 3250);
FORCEPROP 1 LAST PATH I7
J 0
(-7200 3200);
DISPLAY 0.978723 (-7200 3200);
PAINT WHITE (-7200 3200);
DISPLAY INVISIBLE (-7200 3200);
FORCEADD Q_CAP..1
(-1975 3775);
FORCEPROP 1 LAST PART_NUMBER CH622KMEB01
J 0
(-1925 3625);
DISPLAY 0.638298 (-1925 3625);
DISPLAY INVISIBLE (-1925 3625);
FORCEPROP 1 LAST VOLTAGE 4V
J 0
(-1925 3775);
DISPLAY 0.638298 (-1925 3775);
FORCEPROP 1 LAST VALUE 22UF
J 0
(-1925 3825);
DISPLAY 0.638298 (-1925 3825);
FORCEPROP 1 LAST MATERIAL X6S
J 0
(-1925 3675);
DISPLAY 0.638298 (-1925 3675);
FORCEPROP 1 LAST TOLERANCE 20%
J 0
(-1925 3725);
DISPLAY 0.638298 (-1925 3725);
FORCEPROP 1 LAST PACK_TYPE C0402
J 0
(-1925 3575);
DISPLAY 0.638298 (-1925 3575);
FORCEPROP 1 LAST $LOCATION C310
J 0
(-1925 3875);
DISPLAY 0.638298 (-1925 3875);
FORCEPROP 1 LASTPIN (-1975 3875) $PN 1
J 0
(-1965 3855);
DISPLAY 0.787234 (-1965 3855);
FORCEPROP 1 LASTPIN (-1975 3675) $PN 2
J 0
(-1965 3655);
DISPLAY 0.787234 (-1965 3655);
FORCEPROP 2 LAST CDS_LIB pure_quanta
J 0
(-1975 3775);
PAINT MONO (-1975 3775);
DISPLAY INVISIBLE (-1975 3775);
FORCEPROP 1 LAST $LOCATION C310
J 0
(-1925 3975);
DISPLAY 1.021277 (-1925 3975);
DISPLAY INVISIBLE (-1925 3975);
FORCEPROP 2 LAST CDS_LOCATION C310
J 0
(-1925 3975);
DISPLAY 1.021277 (-1925 3975);
DISPLAY INVISIBLE (-1925 3975);
FORCEPROP 2 LAST $SEC 1
J 0
(-1925 3975);
DISPLAY 0.680851 (-1925 3975);
PAINT MONO (-1925 3975);
DISPLAY INVISIBLE (-1925 3975);
FORCEPROP 2 LAST CDS_SEC 1
J 0
(-1925 3975);
DISPLAY 1.021277 (-1925 3975);
DISPLAY INVISIBLE (-1925 3975);
FORCEPROP 1 LAST PATH I70
J 0
(-1925 3925);
DISPLAY 0.978723 (-1925 3925);
PAINT WHITE (-1925 3925);
DISPLAY INVISIBLE (-1925 3925);
FORCEADD Q_CAP..1
(-2275 4625);
FORCEPROP 1 LAST PART_NUMBER CH622KMEB01
J 0
(-2225 4475);
DISPLAY 0.638298 (-2225 4475);
DISPLAY INVISIBLE (-2225 4475);
FORCEPROP 1 LAST TOLERANCE 20%
J 0
(-2225 4575);
DISPLAY 0.638298 (-2225 4575);
FORCEPROP 1 LAST VOLTAGE 4V
J 0
(-2225 4625);
DISPLAY 0.638298 (-2225 4625);
FORCEPROP 1 LAST MATERIAL X6S
J 0
(-2225 4525);
DISPLAY 0.638298 (-2225 4525);
FORCEPROP 1 LAST VALUE 22UF
J 0
(-2225 4675);
DISPLAY 0.638298 (-2225 4675);
FORCEPROP 1 LAST PACK_TYPE C0402
J 0
(-2225 4425);
DISPLAY 0.638298 (-2225 4425);
FORCEPROP 1 LAST $LOCATION C278
J 0
(-2225 4725);
DISPLAY 0.638298 (-2225 4725);
FORCEPROP 1 LASTPIN (-2275 4725) $PN 1
J 0
(-2265 4705);
DISPLAY 0.787234 (-2265 4705);
FORCEPROP 1 LASTPIN (-2275 4525) $PN 2
J 0
(-2265 4505);
DISPLAY 0.787234 (-2265 4505);
FORCEPROP 2 LAST CDS_LIB pure_quanta
J 0
(-2275 4625);
PAINT MONO (-2275 4625);
DISPLAY INVISIBLE (-2275 4625);
FORCEPROP 1 LAST $LOCATION C278
J 0
(-2225 4825);
DISPLAY 1.021277 (-2225 4825);
DISPLAY INVISIBLE (-2225 4825);
FORCEPROP 2 LAST CDS_LOCATION C278
J 0
(-2225 4825);
DISPLAY 1.021277 (-2225 4825);
DISPLAY INVISIBLE (-2225 4825);
FORCEPROP 2 LAST $SEC 1
J 0
(-2225 4825);
DISPLAY 0.680851 (-2225 4825);
PAINT MONO (-2225 4825);
DISPLAY INVISIBLE (-2225 4825);
FORCEPROP 2 LAST CDS_SEC 1
J 0
(-2225 4825);
DISPLAY 1.021277 (-2225 4825);
DISPLAY INVISIBLE (-2225 4825);
FORCEPROP 1 LAST PATH I71
J 0
(-2225 4775);
DISPLAY 0.978723 (-2225 4775);
PAINT WHITE (-2225 4775);
DISPLAY INVISIBLE (-2225 4775);
FORCEADD UNIVERSAL_POWER..1
(-1975 4050);
FORCEPROP 3 LASTPIN (-1975 4000) SIG_NAME PVNN_MAIN_CPU1\g
J 0
(-1965 4010);
DISPLAY 0.659574 (-1965 4010);
PAINT MONO (-1965 4010);
DISPLAY INVISIBLE (-1965 4010);
FORCEPROP 1 LAST HDL_POWER PVNN_MAIN_CPU1
J 1
(-1925 4100);
DISPLAY 1.085106 (-1925 4100);
PAINT GREEN (-1925 4100);
FORCEPROP 2 LAST CDS_LIB logical_power
J 0
(-1975 4050);
DISPLAY INVISIBLE (-1975 4050);
FORCEPROP 1 LAST PATH I72
J 0
(-1925 4075);
DISPLAY 0.872340 (-1925 4075);
PAINT AQUA (-1925 4075);
DISPLAY INVISIBLE (-1925 4075);
FORCEADD Q_CAP..1
(-1825 4625);
FORCEPROP 1 LAST PART_NUMBER CH622KMEB01
J 0
(-1775 4475);
DISPLAY 0.638298 (-1775 4475);
DISPLAY INVISIBLE (-1775 4475);
FORCEPROP 1 LAST TOLERANCE 20%
J 0
(-1775 4575);
DISPLAY 0.638298 (-1775 4575);
FORCEPROP 1 LAST VOLTAGE 4V
J 0
(-1775 4625);
DISPLAY 0.638298 (-1775 4625);
FORCEPROP 1 LAST MATERIAL X6S
J 0
(-1775 4525);
DISPLAY 0.638298 (-1775 4525);
FORCEPROP 1 LAST VALUE 22UF
J 0
(-1775 4675);
DISPLAY 0.638298 (-1775 4675);
FORCEPROP 1 LAST PACK_TYPE C0402
J 0
(-1775 4425);
DISPLAY 0.638298 (-1775 4425);
FORCEPROP 1 LAST $LOCATION C282
J 0
(-1775 4725);
DISPLAY 0.638298 (-1775 4725);
FORCEPROP 1 LASTPIN (-1825 4725) $PN 1
J 0
(-1815 4705);
DISPLAY 0.787234 (-1815 4705);
FORCEPROP 1 LASTPIN (-1825 4525) $PN 2
J 0
(-1815 4505);
DISPLAY 0.787234 (-1815 4505);
FORCEPROP 2 LAST CDS_LIB pure_quanta
J 0
(-1825 4625);
PAINT MONO (-1825 4625);
DISPLAY INVISIBLE (-1825 4625);
FORCEPROP 1 LAST $LOCATION C282
J 0
(-1775 4825);
DISPLAY 1.021277 (-1775 4825);
DISPLAY INVISIBLE (-1775 4825);
FORCEPROP 2 LAST CDS_LOCATION C282
J 0
(-1775 4825);
DISPLAY 1.021277 (-1775 4825);
DISPLAY INVISIBLE (-1775 4825);
FORCEPROP 2 LAST $SEC 1
J 0
(-1775 4825);
DISPLAY 0.680851 (-1775 4825);
PAINT MONO (-1775 4825);
DISPLAY INVISIBLE (-1775 4825);
FORCEPROP 2 LAST CDS_SEC 1
J 0
(-1775 4825);
DISPLAY 1.021277 (-1775 4825);
DISPLAY INVISIBLE (-1775 4825);
FORCEPROP 1 LAST PATH I73
J 0
(-1775 4775);
DISPLAY 0.978723 (-1775 4775);
PAINT WHITE (-1775 4775);
DISPLAY INVISIBLE (-1775 4775);
FORCEADD Q_CAP..1
(-5450 5400);
FORCEPROP 1 LAST PART_NUMBER CH6101MEB03
J 0
(-5400 5250);
DISPLAY 0.638298 (-5400 5250);
DISPLAY INVISIBLE (-5400 5250);
FORCEPROP 1 LAST TOLERANCE 20%
J 0
(-5400 5350);
DISPLAY 0.638298 (-5400 5350);
FORCEPROP 1 LAST VOLTAGE 6.3V
J 0
(-5400 5400);
DISPLAY 0.638298 (-5400 5400);
FORCEPROP 1 LAST MATERIAL X6S
J 0
(-5400 5300);
DISPLAY 0.638298 (-5400 5300);
FORCEPROP 1 LAST PACK_TYPE C0402
J 0
(-5400 5200);
DISPLAY 0.638298 (-5400 5200);
FORCEPROP 1 LAST VALUE 10UF
J 0
(-5400 5450);
DISPLAY 0.638298 (-5400 5450);
FORCEPROP 1 LAST $LOCATION C243
J 0
(-5400 5500);
DISPLAY 0.638298 (-5400 5500);
FORCEPROP 1 LASTPIN (-5450 5500) $PN 1
J 0
(-5440 5480);
DISPLAY 0.787234 (-5440 5480);
FORCEPROP 1 LASTPIN (-5450 5300) $PN 2
J 0
(-5440 5280);
DISPLAY 0.787234 (-5440 5280);
FORCEPROP 2 LAST CDS_LIB pure_quanta
J 0
(-5450 5400);
PAINT MONO (-5450 5400);
DISPLAY INVISIBLE (-5450 5400);
FORCEPROP 1 LAST $LOCATION C243
J 0
(-5400 5600);
DISPLAY 1.021277 (-5400 5600);
DISPLAY INVISIBLE (-5400 5600);
FORCEPROP 2 LAST CDS_LOCATION C243
J 0
(-5400 5600);
DISPLAY 1.021277 (-5400 5600);
DISPLAY INVISIBLE (-5400 5600);
FORCEPROP 2 LAST $SEC 1
J 0
(-5400 5600);
DISPLAY 0.680851 (-5400 5600);
PAINT MONO (-5400 5600);
DISPLAY INVISIBLE (-5400 5600);
FORCEPROP 2 LAST CDS_SEC 1
J 0
(-5400 5600);
DISPLAY 1.021277 (-5400 5600);
DISPLAY INVISIBLE (-5400 5600);
FORCEPROP 1 LAST PATH I74
J 0
(-5400 5550);
DISPLAY 0.978723 (-5400 5550);
PAINT WHITE (-5400 5550);
DISPLAY INVISIBLE (-5400 5550);
FORCEADD Q_CAP..1
(-5000 5400);
FORCEPROP 1 LAST PART_NUMBER CH6101MEB03
J 0
(-4950 5250);
DISPLAY 0.638298 (-4950 5250);
DISPLAY INVISIBLE (-4950 5250);
FORCEPROP 1 LAST TOLERANCE 20%
J 0
(-4950 5350);
DISPLAY 0.638298 (-4950 5350);
FORCEPROP 1 LAST VOLTAGE 6.3V
J 0
(-4950 5400);
DISPLAY 0.638298 (-4950 5400);
FORCEPROP 1 LAST MATERIAL X6S
J 0
(-4950 5300);
DISPLAY 0.638298 (-4950 5300);
FORCEPROP 1 LAST PACK_TYPE C0402
J 0
(-4950 5200);
DISPLAY 0.638298 (-4950 5200);
FORCEPROP 1 LAST VALUE 10UF
J 0
(-4950 5450);
DISPLAY 0.638298 (-4950 5450);
FORCEPROP 1 LAST $LOCATION C248
J 0
(-4950 5500);
DISPLAY 0.638298 (-4950 5500);
FORCEPROP 1 LASTPIN (-5000 5500) $PN 1
J 0
(-4990 5480);
DISPLAY 0.787234 (-4990 5480);
FORCEPROP 1 LASTPIN (-5000 5300) $PN 2
J 0
(-4990 5280);
DISPLAY 0.787234 (-4990 5280);
FORCEPROP 2 LAST CDS_LIB pure_quanta
J 0
(-5000 5400);
PAINT MONO (-5000 5400);
DISPLAY INVISIBLE (-5000 5400);
FORCEPROP 1 LAST $LOCATION C248
J 0
(-4950 5600);
DISPLAY 1.021277 (-4950 5600);
DISPLAY INVISIBLE (-4950 5600);
FORCEPROP 2 LAST CDS_LOCATION C248
J 0
(-4950 5600);
DISPLAY 1.021277 (-4950 5600);
DISPLAY INVISIBLE (-4950 5600);
FORCEPROP 2 LAST $SEC 1
J 0
(-4950 5600);
DISPLAY 0.680851 (-4950 5600);
PAINT MONO (-4950 5600);
DISPLAY INVISIBLE (-4950 5600);
FORCEPROP 2 LAST CDS_SEC 1
J 0
(-4950 5600);
DISPLAY 1.021277 (-4950 5600);
DISPLAY INVISIBLE (-4950 5600);
FORCEPROP 1 LAST PATH I75
J 0
(-4950 5550);
DISPLAY 0.978723 (-4950 5550);
PAINT WHITE (-4950 5550);
DISPLAY INVISIBLE (-4950 5550);
FORCEADD Q_CAP..1
(-5475 6150);
FORCEPROP 1 LAST PART_NUMBER CH6101MEB03
J 0
(-5425 6000);
DISPLAY 0.638298 (-5425 6000);
DISPLAY INVISIBLE (-5425 6000);
FORCEPROP 1 LAST TOLERANCE 20%
J 0
(-5425 6100);
DISPLAY 0.638298 (-5425 6100);
FORCEPROP 1 LAST VALUE 10UF
J 0
(-5425 6200);
DISPLAY 0.638298 (-5425 6200);
FORCEPROP 1 LAST VOLTAGE 6.3V
J 0
(-5425 6150);
DISPLAY 0.638298 (-5425 6150);
FORCEPROP 1 LAST MATERIAL X6S
J 0
(-5425 6050);
DISPLAY 0.638298 (-5425 6050);
FORCEPROP 1 LAST PACK_TYPE C0402
J 0
(-5425 5950);
DISPLAY 0.638298 (-5425 5950);
FORCEPROP 1 LAST $LOCATION C242
J 0
(-5425 6250);
DISPLAY 0.638298 (-5425 6250);
FORCEPROP 1 LASTPIN (-5475 6250) $PN 1
J 0
(-5465 6230);
DISPLAY 0.787234 (-5465 6230);
FORCEPROP 1 LASTPIN (-5475 6050) $PN 2
J 0
(-5465 6030);
DISPLAY 0.787234 (-5465 6030);
FORCEPROP 2 LAST CDS_LIB pure_quanta
J 0
(-5475 6150);
PAINT MONO (-5475 6150);
DISPLAY INVISIBLE (-5475 6150);
FORCEPROP 1 LAST $LOCATION C242
J 0
(-5425 6350);
DISPLAY 1.021277 (-5425 6350);
DISPLAY INVISIBLE (-5425 6350);
FORCEPROP 2 LAST CDS_LOCATION C242
J 0
(-5425 6350);
DISPLAY 1.021277 (-5425 6350);
DISPLAY INVISIBLE (-5425 6350);
FORCEPROP 2 LAST $SEC 1
J 0
(-5425 6350);
DISPLAY 0.680851 (-5425 6350);
PAINT MONO (-5425 6350);
DISPLAY INVISIBLE (-5425 6350);
FORCEPROP 2 LAST CDS_SEC 1
J 0
(-5425 6350);
DISPLAY 1.021277 (-5425 6350);
DISPLAY INVISIBLE (-5425 6350);
FORCEPROP 1 LAST PATH I76
J 0
(-5425 6300);
DISPLAY 0.978723 (-5425 6300);
PAINT WHITE (-5425 6300);
DISPLAY INVISIBLE (-5425 6300);
FORCEADD Q_CAP..1
(-5475 6925);
FORCEPROP 1 LAST PART_NUMBER CH6101MEB03
J 0
(-5425 6775);
DISPLAY 0.638298 (-5425 6775);
DISPLAY INVISIBLE (-5425 6775);
FORCEPROP 1 LAST TOLERANCE 20%
J 0
(-5425 6875);
DISPLAY 0.638298 (-5425 6875);
FORCEPROP 1 LAST VOLTAGE 6.3V
J 0
(-5425 6925);
DISPLAY 0.638298 (-5425 6925);
FORCEPROP 1 LAST MATERIAL X6S
J 0
(-5425 6825);
DISPLAY 0.638298 (-5425 6825);
FORCEPROP 1 LAST PACK_TYPE C0402
J 0
(-5425 6725);
DISPLAY 0.638298 (-5425 6725);
FORCEPROP 1 LAST VALUE 10UF
J 0
(-5425 6975);
DISPLAY 0.638298 (-5425 6975);
FORCEPROP 1 LAST $LOCATION C241
J 0
(-5425 7025);
DISPLAY 0.638298 (-5425 7025);
FORCEPROP 1 LASTPIN (-5475 7025) $PN 1
J 0
(-5465 7005);
DISPLAY 0.787234 (-5465 7005);
FORCEPROP 1 LASTPIN (-5475 6825) $PN 2
J 0
(-5465 6805);
DISPLAY 0.787234 (-5465 6805);
FORCEPROP 2 LAST CDS_LIB pure_quanta
J 0
(-5475 6925);
PAINT MONO (-5475 6925);
DISPLAY INVISIBLE (-5475 6925);
FORCEPROP 1 LAST $LOCATION C241
J 0
(-5425 7125);
DISPLAY 1.021277 (-5425 7125);
DISPLAY INVISIBLE (-5425 7125);
FORCEPROP 2 LAST CDS_LOCATION C241
J 0
(-5425 7125);
DISPLAY 1.021277 (-5425 7125);
DISPLAY INVISIBLE (-5425 7125);
FORCEPROP 2 LAST $SEC 1
J 0
(-5425 7125);
DISPLAY 0.680851 (-5425 7125);
PAINT MONO (-5425 7125);
DISPLAY INVISIBLE (-5425 7125);
FORCEPROP 2 LAST CDS_SEC 1
J 0
(-5425 7125);
DISPLAY 1.021277 (-5425 7125);
DISPLAY INVISIBLE (-5425 7125);
FORCEPROP 1 LAST PATH I77
J 0
(-5425 7075);
DISPLAY 0.978723 (-5425 7075);
PAINT WHITE (-5425 7075);
DISPLAY INVISIBLE (-5425 7075);
FORCEADD Q_CAP..1
(-5025 6150);
FORCEPROP 1 LAST PART_NUMBER CH6101MEB03
J 0
(-4975 6000);
DISPLAY 0.638298 (-4975 6000);
DISPLAY INVISIBLE (-4975 6000);
FORCEPROP 1 LAST TOLERANCE 20%
J 0
(-4975 6100);
DISPLAY 0.638298 (-4975 6100);
FORCEPROP 1 LAST VALUE 10UF
J 0
(-4975 6200);
DISPLAY 0.638298 (-4975 6200);
FORCEPROP 1 LAST VOLTAGE 6.3V
J 0
(-4975 6150);
DISPLAY 0.638298 (-4975 6150);
FORCEPROP 1 LAST PACK_TYPE C0402
J 0
(-4975 5950);
DISPLAY 0.638298 (-4975 5950);
FORCEPROP 1 LAST MATERIAL X6S
J 0
(-4975 6050);
DISPLAY 0.638298 (-4975 6050);
FORCEPROP 1 LAST $LOCATION C247
J 0
(-4975 6250);
DISPLAY 0.638298 (-4975 6250);
FORCEPROP 1 LASTPIN (-5025 6250) $PN 1
J 0
(-5015 6230);
DISPLAY 0.787234 (-5015 6230);
FORCEPROP 1 LASTPIN (-5025 6050) $PN 2
J 0
(-5015 6030);
DISPLAY 0.787234 (-5015 6030);
FORCEPROP 2 LAST CDS_LIB pure_quanta
J 0
(-5025 6150);
PAINT MONO (-5025 6150);
DISPLAY INVISIBLE (-5025 6150);
FORCEPROP 1 LAST $LOCATION C247
J 0
(-4975 6350);
DISPLAY 1.021277 (-4975 6350);
DISPLAY INVISIBLE (-4975 6350);
FORCEPROP 2 LAST CDS_LOCATION C247
J 0
(-4975 6350);
DISPLAY 1.021277 (-4975 6350);
DISPLAY INVISIBLE (-4975 6350);
FORCEPROP 2 LAST $SEC 1
J 0
(-4975 6350);
DISPLAY 0.680851 (-4975 6350);
PAINT MONO (-4975 6350);
DISPLAY INVISIBLE (-4975 6350);
FORCEPROP 2 LAST CDS_SEC 1
J 0
(-4975 6350);
DISPLAY 1.021277 (-4975 6350);
DISPLAY INVISIBLE (-4975 6350);
FORCEPROP 1 LAST PATH I78
J 0
(-4975 6300);
DISPLAY 0.978723 (-4975 6300);
PAINT WHITE (-4975 6300);
DISPLAY INVISIBLE (-4975 6300);
FORCEADD Q_CAP..1
(-5025 6925);
FORCEPROP 1 LAST PART_NUMBER CH6101MEB03
J 0
(-4975 6775);
DISPLAY 0.638298 (-4975 6775);
DISPLAY INVISIBLE (-4975 6775);
FORCEPROP 1 LAST TOLERANCE 20%
J 0
(-4975 6875);
DISPLAY 0.638298 (-4975 6875);
FORCEPROP 1 LAST VOLTAGE 6.3V
J 0
(-4975 6925);
DISPLAY 0.638298 (-4975 6925);
FORCEPROP 1 LAST MATERIAL X6S
J 0
(-4975 6825);
DISPLAY 0.638298 (-4975 6825);
FORCEPROP 1 LAST PACK_TYPE C0402
J 0
(-4975 6725);
DISPLAY 0.638298 (-4975 6725);
FORCEPROP 1 LAST VALUE 10UF
J 0
(-4975 6975);
DISPLAY 0.638298 (-4975 6975);
FORCEPROP 1 LAST $LOCATION C246
J 0
(-4975 7025);
DISPLAY 0.638298 (-4975 7025);
FORCEPROP 1 LASTPIN (-5025 7025) $PN 1
J 0
(-5015 7005);
DISPLAY 0.787234 (-5015 7005);
FORCEPROP 1 LASTPIN (-5025 6825) $PN 2
J 0
(-5015 6805);
DISPLAY 0.787234 (-5015 6805);
FORCEPROP 2 LAST CDS_LIB pure_quanta
J 0
(-5025 6925);
PAINT MONO (-5025 6925);
DISPLAY INVISIBLE (-5025 6925);
FORCEPROP 1 LAST $LOCATION C246
J 0
(-4975 7125);
DISPLAY 1.021277 (-4975 7125);
DISPLAY INVISIBLE (-4975 7125);
FORCEPROP 2 LAST CDS_LOCATION C246
J 0
(-4975 7125);
DISPLAY 1.021277 (-4975 7125);
DISPLAY INVISIBLE (-4975 7125);
FORCEPROP 2 LAST $SEC 1
J 0
(-4975 7125);
DISPLAY 0.680851 (-4975 7125);
PAINT MONO (-4975 7125);
DISPLAY INVISIBLE (-4975 7125);
FORCEPROP 2 LAST CDS_SEC 1
J 0
(-4975 7125);
DISPLAY 1.021277 (-4975 7125);
DISPLAY INVISIBLE (-4975 7125);
FORCEPROP 1 LAST PATH I79
J 0
(-4975 7075);
DISPLAY 0.978723 (-4975 7075);
PAINT WHITE (-4975 7075);
DISPLAY INVISIBLE (-4975 7075);
FORCEADD Q_CAP..1
(-6800 3050);
FORCEPROP 1 LAST PART_NUMBER CH622KMEB01
J 0
(-6750 2900);
DISPLAY 0.638298 (-6750 2900);
DISPLAY INVISIBLE (-6750 2900);
FORCEPROP 1 LAST VOLTAGE 4V
J 0
(-6750 3050);
DISPLAY 0.638298 (-6750 3050);
FORCEPROP 1 LAST PACK_TYPE C0402
J 0
(-6750 2850);
DISPLAY 0.638298 (-6750 2850);
FORCEPROP 1 LAST MATERIAL X6S
J 0
(-6750 2950);
DISPLAY 0.638298 (-6750 2950);
FORCEPROP 1 LAST VALUE 22UF
J 0
(-6750 3100);
DISPLAY 0.638298 (-6750 3100);
FORCEPROP 1 LAST TOLERANCE 20%
J 0
(-6750 3000);
DISPLAY 0.638298 (-6750 3000);
FORCEPROP 1 LAST $LOCATION C425
J 0
(-6750 3150);
DISPLAY 0.978723 (-6750 3150);
FORCEPROP 1 LASTPIN (-6800 3150) $PN 1
J 0
(-6790 3130);
DISPLAY 0.787234 (-6790 3130);
FORCEPROP 1 LASTPIN (-6800 2950) $PN 2
J 0
(-6790 2930);
DISPLAY 0.787234 (-6790 2930);
FORCEPROP 2 LAST CDS_LIB pure_quanta
J 0
(-6800 3050);
PAINT MONO (-6800 3050);
DISPLAY INVISIBLE (-6800 3050);
FORCEPROP 2 LAST CDS_LOCATION C425
J 0
(-6750 3250);
DISPLAY 1.021277 (-6750 3250);
DISPLAY INVISIBLE (-6750 3250);
FORCEPROP 2 LAST $SEC 1
J 0
(-6750 3250);
DISPLAY 0.680851 (-6750 3250);
PAINT MONO (-6750 3250);
DISPLAY INVISIBLE (-6750 3250);
FORCEPROP 2 LAST CDS_SEC 1
J 0
(-6750 3250);
DISPLAY 1.021277 (-6750 3250);
DISPLAY INVISIBLE (-6750 3250);
FORCEPROP 1 LAST PATH I8
J 0
(-6750 3200);
DISPLAY 0.978723 (-6750 3200);
PAINT WHITE (-6750 3200);
DISPLAY INVISIBLE (-6750 3200);
FORCEADD Q_CAP..1
(-4550 5400);
FORCEPROP 1 LAST PART_NUMBER CH6101MEB03
J 0
(-4500 5250);
DISPLAY 0.638298 (-4500 5250);
DISPLAY INVISIBLE (-4500 5250);
FORCEPROP 1 LAST TOLERANCE 20%
J 0
(-4500 5350);
DISPLAY 0.638298 (-4500 5350);
FORCEPROP 1 LAST VOLTAGE 6.3V
J 0
(-4500 5400);
DISPLAY 0.638298 (-4500 5400);
FORCEPROP 1 LAST MATERIAL X6S
J 0
(-4500 5300);
DISPLAY 0.638298 (-4500 5300);
FORCEPROP 1 LAST PACK_TYPE C0402
J 0
(-4500 5200);
DISPLAY 0.638298 (-4500 5200);
FORCEPROP 1 LAST VALUE 10UF
J 0
(-4500 5450);
DISPLAY 0.638298 (-4500 5450);
FORCEPROP 1 LAST $LOCATION C253
J 0
(-4500 5500);
DISPLAY 0.638298 (-4500 5500);
FORCEPROP 1 LASTPIN (-4550 5500) $PN 1
J 0
(-4540 5480);
DISPLAY 0.787234 (-4540 5480);
FORCEPROP 1 LASTPIN (-4550 5300) $PN 2
J 0
(-4540 5280);
DISPLAY 0.787234 (-4540 5280);
FORCEPROP 2 LAST CDS_LIB pure_quanta
J 0
(-4550 5400);
PAINT MONO (-4550 5400);
DISPLAY INVISIBLE (-4550 5400);
FORCEPROP 1 LAST $LOCATION C253
J 0
(-4500 5600);
DISPLAY 1.021277 (-4500 5600);
DISPLAY INVISIBLE (-4500 5600);
FORCEPROP 2 LAST CDS_LOCATION C253
J 0
(-4500 5600);
DISPLAY 1.021277 (-4500 5600);
DISPLAY INVISIBLE (-4500 5600);
FORCEPROP 2 LAST $SEC 1
J 0
(-4500 5600);
DISPLAY 0.680851 (-4500 5600);
PAINT MONO (-4500 5600);
DISPLAY INVISIBLE (-4500 5600);
FORCEPROP 2 LAST CDS_SEC 1
J 0
(-4500 5600);
DISPLAY 1.021277 (-4500 5600);
DISPLAY INVISIBLE (-4500 5600);
FORCEPROP 1 LAST PATH I80
J 0
(-4500 5550);
DISPLAY 0.978723 (-4500 5550);
PAINT WHITE (-4500 5550);
DISPLAY INVISIBLE (-4500 5550);
FORCEADD Q_CAP..1
(-4100 5400);
FORCEPROP 1 LAST PART_NUMBER CH6101MEB03
J 0
(-4050 5250);
DISPLAY 0.638298 (-4050 5250);
DISPLAY INVISIBLE (-4050 5250);
FORCEPROP 1 LAST VOLTAGE 6.3V
J 0
(-4050 5400);
DISPLAY 0.638298 (-4050 5400);
FORCEPROP 1 LAST TOLERANCE 20%
J 0
(-4050 5350);
DISPLAY 0.638298 (-4050 5350);
FORCEPROP 1 LAST VALUE 10UF
J 0
(-4050 5450);
DISPLAY 0.638298 (-4050 5450);
FORCEPROP 1 LAST PACK_TYPE C0402
J 0
(-4050 5200);
DISPLAY 0.638298 (-4050 5200);
FORCEPROP 1 LAST MATERIAL X6S
J 0
(-4050 5300);
DISPLAY 0.638298 (-4050 5300);
FORCEPROP 1 LAST $LOCATION C258
J 0
(-4050 5500);
DISPLAY 0.638298 (-4050 5500);
FORCEPROP 1 LASTPIN (-4100 5500) $PN 1
J 0
(-4090 5480);
DISPLAY 0.787234 (-4090 5480);
FORCEPROP 1 LASTPIN (-4100 5300) $PN 2
J 0
(-4090 5280);
DISPLAY 0.787234 (-4090 5280);
FORCEPROP 2 LAST CDS_LIB pure_quanta
J 0
(-4100 5400);
PAINT MONO (-4100 5400);
DISPLAY INVISIBLE (-4100 5400);
FORCEPROP 1 LAST $LOCATION C258
J 0
(-4050 5600);
DISPLAY 1.021277 (-4050 5600);
DISPLAY INVISIBLE (-4050 5600);
FORCEPROP 2 LAST CDS_LOCATION C258
J 0
(-4050 5600);
DISPLAY 1.021277 (-4050 5600);
DISPLAY INVISIBLE (-4050 5600);
FORCEPROP 2 LAST $SEC 1
J 0
(-4050 5600);
DISPLAY 0.680851 (-4050 5600);
PAINT MONO (-4050 5600);
DISPLAY INVISIBLE (-4050 5600);
FORCEPROP 2 LAST CDS_SEC 1
J 0
(-4050 5600);
DISPLAY 1.021277 (-4050 5600);
DISPLAY INVISIBLE (-4050 5600);
FORCEPROP 1 LAST PATH I81
J 0
(-4050 5550);
DISPLAY 0.978723 (-4050 5550);
PAINT WHITE (-4050 5550);
DISPLAY INVISIBLE (-4050 5550);
FORCEADD Q_CAP..1
(-4575 6150);
FORCEPROP 1 LAST PART_NUMBER CH6101MEB03
J 0
(-4525 6000);
DISPLAY 0.638298 (-4525 6000);
DISPLAY INVISIBLE (-4525 6000);
FORCEPROP 1 LAST TOLERANCE 20%
J 0
(-4525 6100);
DISPLAY 0.638298 (-4525 6100);
FORCEPROP 1 LAST VALUE 10UF
J 0
(-4525 6200);
DISPLAY 0.638298 (-4525 6200);
FORCEPROP 1 LAST VOLTAGE 6.3V
J 0
(-4525 6150);
DISPLAY 0.638298 (-4525 6150);
FORCEPROP 1 LAST PACK_TYPE C0402
J 0
(-4525 5950);
DISPLAY 0.638298 (-4525 5950);
FORCEPROP 1 LAST MATERIAL X6S
J 0
(-4525 6050);
DISPLAY 0.638298 (-4525 6050);
FORCEPROP 1 LAST $LOCATION C252
J 0
(-4525 6250);
DISPLAY 0.638298 (-4525 6250);
FORCEPROP 1 LASTPIN (-4575 6250) $PN 1
J 0
(-4565 6230);
DISPLAY 0.787234 (-4565 6230);
FORCEPROP 1 LASTPIN (-4575 6050) $PN 2
J 0
(-4565 6030);
DISPLAY 0.787234 (-4565 6030);
FORCEPROP 2 LAST CDS_LIB pure_quanta
J 0
(-4575 6150);
PAINT MONO (-4575 6150);
DISPLAY INVISIBLE (-4575 6150);
FORCEPROP 1 LAST $LOCATION C252
J 0
(-4525 6350);
DISPLAY 1.021277 (-4525 6350);
DISPLAY INVISIBLE (-4525 6350);
FORCEPROP 2 LAST CDS_LOCATION C252
J 0
(-4525 6350);
DISPLAY 1.021277 (-4525 6350);
DISPLAY INVISIBLE (-4525 6350);
FORCEPROP 2 LAST $SEC 1
J 0
(-4525 6350);
DISPLAY 0.680851 (-4525 6350);
PAINT MONO (-4525 6350);
DISPLAY INVISIBLE (-4525 6350);
FORCEPROP 2 LAST CDS_SEC 1
J 0
(-4525 6350);
DISPLAY 1.021277 (-4525 6350);
DISPLAY INVISIBLE (-4525 6350);
FORCEPROP 1 LAST PATH I82
J 0
(-4525 6300);
DISPLAY 0.978723 (-4525 6300);
PAINT WHITE (-4525 6300);
DISPLAY INVISIBLE (-4525 6300);
FORCEADD Q_CAP..1
(-4575 6925);
FORCEPROP 1 LAST PART_NUMBER CH6101MEB03
J 0
(-4525 6775);
DISPLAY 0.638298 (-4525 6775);
DISPLAY INVISIBLE (-4525 6775);
FORCEPROP 1 LAST TOLERANCE 20%
J 0
(-4525 6875);
DISPLAY 0.638298 (-4525 6875);
FORCEPROP 1 LAST VOLTAGE 6.3V
J 0
(-4525 6925);
DISPLAY 0.638298 (-4525 6925);
FORCEPROP 1 LAST MATERIAL X6S
J 0
(-4525 6825);
DISPLAY 0.638298 (-4525 6825);
FORCEPROP 1 LAST PACK_TYPE C0402
J 0
(-4525 6725);
DISPLAY 0.638298 (-4525 6725);
FORCEPROP 1 LAST VALUE 10UF
J 0
(-4525 6975);
DISPLAY 0.638298 (-4525 6975);
FORCEPROP 1 LAST $LOCATION C251
J 0
(-4525 7025);
DISPLAY 0.638298 (-4525 7025);
FORCEPROP 1 LASTPIN (-4575 7025) $PN 1
J 0
(-4565 7005);
DISPLAY 0.787234 (-4565 7005);
FORCEPROP 1 LASTPIN (-4575 6825) $PN 2
J 0
(-4565 6805);
DISPLAY 0.787234 (-4565 6805);
FORCEPROP 2 LAST CDS_LIB pure_quanta
J 0
(-4575 6925);
PAINT MONO (-4575 6925);
DISPLAY INVISIBLE (-4575 6925);
FORCEPROP 1 LAST $LOCATION C251
J 0
(-4525 7125);
DISPLAY 1.021277 (-4525 7125);
DISPLAY INVISIBLE (-4525 7125);
FORCEPROP 2 LAST CDS_LOCATION C251
J 0
(-4525 7125);
DISPLAY 1.021277 (-4525 7125);
DISPLAY INVISIBLE (-4525 7125);
FORCEPROP 2 LAST $SEC 1
J 0
(-4525 7125);
DISPLAY 0.680851 (-4525 7125);
PAINT MONO (-4525 7125);
DISPLAY INVISIBLE (-4525 7125);
FORCEPROP 2 LAST CDS_SEC 1
J 0
(-4525 7125);
DISPLAY 1.021277 (-4525 7125);
DISPLAY INVISIBLE (-4525 7125);
FORCEPROP 1 LAST PATH I83
J 0
(-4525 7075);
DISPLAY 0.978723 (-4525 7075);
PAINT WHITE (-4525 7075);
DISPLAY INVISIBLE (-4525 7075);
FORCEADD Q_CAP..1
(-4125 6150);
FORCEPROP 1 LAST PART_NUMBER CH6101MEB03
J 0
(-4075 6000);
DISPLAY 0.638298 (-4075 6000);
DISPLAY INVISIBLE (-4075 6000);
FORCEPROP 1 LAST VOLTAGE 6.3V
J 0
(-4075 6150);
DISPLAY 0.638298 (-4075 6150);
FORCEPROP 1 LAST VALUE 10UF
J 0
(-4075 6200);
DISPLAY 0.638298 (-4075 6200);
FORCEPROP 1 LAST TOLERANCE 20%
J 0
(-4075 6100);
DISPLAY 0.638298 (-4075 6100);
FORCEPROP 1 LAST MATERIAL X6S
J 0
(-4075 6050);
DISPLAY 0.638298 (-4075 6050);
FORCEPROP 1 LAST PACK_TYPE C0402
J 0
(-4075 5950);
DISPLAY 0.638298 (-4075 5950);
FORCEPROP 1 LAST $LOCATION C257
J 0
(-4075 6250);
DISPLAY 0.638298 (-4075 6250);
FORCEPROP 1 LASTPIN (-4125 6250) $PN 1
J 0
(-4115 6230);
DISPLAY 0.787234 (-4115 6230);
FORCEPROP 1 LASTPIN (-4125 6050) $PN 2
J 0
(-4115 6030);
DISPLAY 0.787234 (-4115 6030);
FORCEPROP 2 LAST CDS_LIB pure_quanta
J 0
(-4125 6150);
PAINT MONO (-4125 6150);
DISPLAY INVISIBLE (-4125 6150);
FORCEPROP 1 LAST $LOCATION C257
J 0
(-4075 6350);
DISPLAY 1.021277 (-4075 6350);
DISPLAY INVISIBLE (-4075 6350);
FORCEPROP 2 LAST CDS_LOCATION C257
J 0
(-4075 6350);
DISPLAY 1.021277 (-4075 6350);
DISPLAY INVISIBLE (-4075 6350);
FORCEPROP 2 LAST $SEC 1
J 0
(-4075 6350);
DISPLAY 0.680851 (-4075 6350);
PAINT MONO (-4075 6350);
DISPLAY INVISIBLE (-4075 6350);
FORCEPROP 2 LAST CDS_SEC 1
J 0
(-4075 6350);
DISPLAY 1.021277 (-4075 6350);
DISPLAY INVISIBLE (-4075 6350);
FORCEPROP 1 LAST PATH I84
J 0
(-4075 6300);
DISPLAY 0.978723 (-4075 6300);
PAINT WHITE (-4075 6300);
DISPLAY INVISIBLE (-4075 6300);
FORCEADD Q_CAP..1
(-4125 6925);
FORCEPROP 1 LAST PART_NUMBER CH6101MEB03
J 0
(-4075 6775);
DISPLAY 0.638298 (-4075 6775);
DISPLAY INVISIBLE (-4075 6775);
FORCEPROP 1 LAST VOLTAGE 6.3V
J 0
(-4075 6925);
DISPLAY 0.638298 (-4075 6925);
FORCEPROP 1 LAST TOLERANCE 20%
J 0
(-4075 6875);
DISPLAY 0.638298 (-4075 6875);
FORCEPROP 1 LAST VALUE 10UF
J 0
(-4075 6975);
DISPLAY 0.638298 (-4075 6975);
FORCEPROP 1 LAST PACK_TYPE C0402
J 0
(-4075 6725);
DISPLAY 0.638298 (-4075 6725);
FORCEPROP 1 LAST MATERIAL X6S
J 0
(-4075 6825);
DISPLAY 0.638298 (-4075 6825);
FORCEPROP 1 LAST $LOCATION C256
J 0
(-4075 7025);
DISPLAY 0.638298 (-4075 7025);
FORCEPROP 1 LASTPIN (-4125 7025) $PN 1
J 0
(-4115 7005);
DISPLAY 0.787234 (-4115 7005);
FORCEPROP 1 LASTPIN (-4125 6825) $PN 2
J 0
(-4115 6805);
DISPLAY 0.787234 (-4115 6805);
FORCEPROP 2 LAST CDS_LIB pure_quanta
J 0
(-4125 6925);
PAINT MONO (-4125 6925);
DISPLAY INVISIBLE (-4125 6925);
FORCEPROP 1 LAST $LOCATION C256
J 0
(-4075 7125);
DISPLAY 1.021277 (-4075 7125);
DISPLAY INVISIBLE (-4075 7125);
FORCEPROP 2 LAST CDS_LOCATION C256
J 0
(-4075 7125);
DISPLAY 1.021277 (-4075 7125);
DISPLAY INVISIBLE (-4075 7125);
FORCEPROP 2 LAST $SEC 1
J 0
(-4075 7125);
DISPLAY 0.680851 (-4075 7125);
PAINT MONO (-4075 7125);
DISPLAY INVISIBLE (-4075 7125);
FORCEPROP 2 LAST CDS_SEC 1
J 0
(-4075 7125);
DISPLAY 1.021277 (-4075 7125);
DISPLAY INVISIBLE (-4075 7125);
FORCEPROP 1 LAST PATH I85
J 0
(-4075 7075);
DISPLAY 0.978723 (-4075 7075);
PAINT WHITE (-4075 7075);
DISPLAY INVISIBLE (-4075 7075);
FORCEADD Q_CAP..1
(-3650 5400);
FORCEPROP 1 LAST PART_NUMBER CH6101MEB03
J 0
(-3600 5250);
DISPLAY 0.638298 (-3600 5250);
DISPLAY INVISIBLE (-3600 5250);
FORCEPROP 1 LAST VOLTAGE 6.3V
J 0
(-3600 5400);
DISPLAY 0.638298 (-3600 5400);
FORCEPROP 1 LAST TOLERANCE 20%
J 0
(-3600 5350);
DISPLAY 0.638298 (-3600 5350);
FORCEPROP 1 LAST VALUE 10UF
J 0
(-3600 5450);
DISPLAY 0.638298 (-3600 5450);
FORCEPROP 1 LAST PACK_TYPE C0402
J 0
(-3600 5200);
DISPLAY 0.638298 (-3600 5200);
FORCEPROP 1 LAST MATERIAL X6S
J 0
(-3600 5300);
DISPLAY 0.638298 (-3600 5300);
FORCEPROP 1 LAST $LOCATION C263
J 0
(-3600 5500);
DISPLAY 0.638298 (-3600 5500);
FORCEPROP 1 LASTPIN (-3650 5500) $PN 1
J 0
(-3640 5480);
DISPLAY 0.787234 (-3640 5480);
FORCEPROP 1 LASTPIN (-3650 5300) $PN 2
J 0
(-3640 5280);
DISPLAY 0.787234 (-3640 5280);
FORCEPROP 2 LAST CDS_LIB pure_quanta
J 0
(-3650 5400);
PAINT MONO (-3650 5400);
DISPLAY INVISIBLE (-3650 5400);
FORCEPROP 1 LAST $LOCATION C263
J 0
(-3600 5600);
DISPLAY 1.021277 (-3600 5600);
DISPLAY INVISIBLE (-3600 5600);
FORCEPROP 2 LAST CDS_LOCATION C263
J 0
(-3600 5600);
DISPLAY 1.021277 (-3600 5600);
DISPLAY INVISIBLE (-3600 5600);
FORCEPROP 2 LAST $SEC 1
J 0
(-3600 5600);
DISPLAY 0.680851 (-3600 5600);
PAINT MONO (-3600 5600);
DISPLAY INVISIBLE (-3600 5600);
FORCEPROP 2 LAST CDS_SEC 1
J 0
(-3600 5600);
DISPLAY 1.021277 (-3600 5600);
DISPLAY INVISIBLE (-3600 5600);
FORCEPROP 1 LAST PATH I86
J 0
(-3600 5550);
DISPLAY 0.978723 (-3600 5550);
PAINT WHITE (-3600 5550);
DISPLAY INVISIBLE (-3600 5550);
FORCEADD UNIVERSAL_GND..1
(-3225 5800);
FORCEPROP 3 LASTPIN (-3225 5850) SIG_NAME GND\g
J 0
(-3215 5860);
DISPLAY 0.659574 (-3215 5860);
PAINT MONO (-3215 5860);
DISPLAY INVISIBLE (-3215 5860);
FORCEPROP 2 LAST CDS_LIB logical_power
J 0
(-3225 5800);
PAINT MONO (-3225 5800);
DISPLAY INVISIBLE (-3225 5800);
FORCEPROP 1 LAST HDL_POWER GND
J 1
(-3200 5725);
DISPLAY 0.872340 (-3200 5725);
PAINT GREEN (-3200 5725);
DISPLAY INVISIBLE (-3200 5725);
FORCEPROP 1 LAST PATH I87
J 0
(-3150 5800);
DISPLAY 0.872340 (-3150 5800);
PAINT AQUA (-3150 5800);
DISPLAY INVISIBLE (-3150 5800);
FORCEADD Q_CAP..1
(-3200 5400);
FORCEPROP 1 LAST PART_NUMBER CH6101MEB03
J 0
(-3150 5250);
DISPLAY 0.638298 (-3150 5250);
DISPLAY INVISIBLE (-3150 5250);
FORCEPROP 1 LAST VOLTAGE 6.3V
J 0
(-3150 5400);
DISPLAY 0.638298 (-3150 5400);
FORCEPROP 1 LAST TOLERANCE 20%
J 0
(-3150 5350);
DISPLAY 0.638298 (-3150 5350);
FORCEPROP 1 LAST VALUE 10UF
J 0
(-3150 5450);
DISPLAY 0.638298 (-3150 5450);
FORCEPROP 1 LAST PACK_TYPE C0402
J 0
(-3150 5200);
DISPLAY 0.638298 (-3150 5200);
FORCEPROP 1 LAST MATERIAL X6S
J 0
(-3150 5300);
DISPLAY 0.638298 (-3150 5300);
FORCEPROP 1 LAST $LOCATION C268
J 0
(-3150 5500);
DISPLAY 0.638298 (-3150 5500);
FORCEPROP 1 LASTPIN (-3200 5500) $PN 1
J 0
(-3190 5480);
DISPLAY 0.787234 (-3190 5480);
FORCEPROP 1 LASTPIN (-3200 5300) $PN 2
J 0
(-3190 5280);
DISPLAY 0.787234 (-3190 5280);
FORCEPROP 2 LAST CDS_LIB pure_quanta
J 0
(-3200 5400);
PAINT MONO (-3200 5400);
DISPLAY INVISIBLE (-3200 5400);
FORCEPROP 1 LAST $LOCATION C268
J 0
(-3150 5600);
DISPLAY 1.021277 (-3150 5600);
DISPLAY INVISIBLE (-3150 5600);
FORCEPROP 2 LAST CDS_LOCATION C268
J 0
(-3150 5600);
DISPLAY 1.021277 (-3150 5600);
DISPLAY INVISIBLE (-3150 5600);
FORCEPROP 2 LAST $SEC 1
J 0
(-3150 5600);
DISPLAY 0.680851 (-3150 5600);
PAINT MONO (-3150 5600);
DISPLAY INVISIBLE (-3150 5600);
FORCEPROP 2 LAST CDS_SEC 1
J 0
(-3150 5600);
DISPLAY 1.021277 (-3150 5600);
DISPLAY INVISIBLE (-3150 5600);
FORCEPROP 1 LAST PATH I88
J 0
(-3150 5550);
DISPLAY 0.978723 (-3150 5550);
PAINT WHITE (-3150 5550);
DISPLAY INVISIBLE (-3150 5550);
FORCEADD UNIVERSAL_GND..1
(-3200 5050);
FORCEPROP 3 LASTPIN (-3200 5100) SIG_NAME GND\g
J 0
(-3190 5110);
DISPLAY 0.659574 (-3190 5110);
PAINT MONO (-3190 5110);
DISPLAY INVISIBLE (-3190 5110);
FORCEPROP 2 LAST CDS_LIB logical_power
J 0
(-3200 5050);
PAINT MONO (-3200 5050);
DISPLAY INVISIBLE (-3200 5050);
FORCEPROP 1 LAST HDL_POWER GND
J 1
(-3175 4975);
DISPLAY 0.872340 (-3175 4975);
PAINT GREEN (-3175 4975);
DISPLAY INVISIBLE (-3175 4975);
FORCEPROP 1 LAST PATH I89
J 0
(-3125 5050);
DISPLAY 0.872340 (-3125 5050);
PAINT AQUA (-3125 5050);
DISPLAY INVISIBLE (-3125 5050);
FORCEADD UNIVERSAL_POWER..1
(-7250 3325);
FORCEPROP 3 LASTPIN (-7250 3275) SIG_NAME PVCCD_HV_CPU1\g
J 0
(-7240 3285);
DISPLAY 0.659574 (-7240 3285);
PAINT MONO (-7240 3285);
DISPLAY INVISIBLE (-7240 3285);
FORCEPROP 1 LAST HDL_POWER PVCCD_HV_CPU1
J 1
(-7025 3375);
DISPLAY 0.872340 (-7025 3375);
PAINT GREEN (-7025 3375);
FORCEPROP 2 LAST CDS_LIB logical_power
J 0
(-7250 3325);
PAINT MONO (-7250 3325);
DISPLAY INVISIBLE (-7250 3325);
FORCEPROP 1 LAST PATH I9
J 0
(-7200 3350);
DISPLAY 0.872340 (-7200 3350);
PAINT AQUA (-7200 3350);
DISPLAY INVISIBLE (-7200 3350);
FORCEADD UNIVERSAL_POWER..1
(-2725 4900);
FORCEPROP 3 LASTPIN (-2725 4850) SIG_NAME PVCCIN_CPU1\g
J 0
(-2715 4860);
DISPLAY 0.659574 (-2715 4860);
PAINT MONO (-2715 4860);
DISPLAY INVISIBLE (-2715 4860);
FORCEPROP 1 LAST HDL_POWER PVCCIN_CPU1
J 1
(-2525 4950);
DISPLAY 0.872340 (-2525 4950);
PAINT GREEN (-2525 4950);
FORCEPROP 2 LAST CDS_LIB logical_power
J 0
(-2725 4900);
DISPLAY INVISIBLE (-2725 4900);
FORCEPROP 1 LAST PATH I90
J 0
(-2675 4925);
DISPLAY 0.872340 (-2675 4925);
PAINT AQUA (-2675 4925);
DISPLAY INVISIBLE (-2675 4925);
FORCEADD Q_CAP..1
(-2725 5400);
FORCEPROP 1 LAST PART_NUMBER CH622KMEB01
J 0
(-2675 5250);
DISPLAY 0.638298 (-2675 5250);
DISPLAY INVISIBLE (-2675 5250);
FORCEPROP 1 LAST VOLTAGE 4V
J 0
(-2675 5400);
DISPLAY 0.638298 (-2675 5400);
FORCEPROP 1 LAST PACK_TYPE C0402
J 0
(-2675 5200);
DISPLAY 0.638298 (-2675 5200);
FORCEPROP 1 LAST MATERIAL X6S
J 0
(-2675 5300);
DISPLAY 0.638298 (-2675 5300);
FORCEPROP 1 LAST VALUE 22UF
J 0
(-2675 5450);
DISPLAY 0.638298 (-2675 5450);
FORCEPROP 1 LAST TOLERANCE 20%
J 0
(-2675 5350);
DISPLAY 0.638298 (-2675 5350);
FORCEPROP 1 LAST $LOCATION C273
J 0
(-2675 5500);
DISPLAY 0.638298 (-2675 5500);
FORCEPROP 1 LASTPIN (-2725 5500) $PN 1
J 0
(-2715 5480);
DISPLAY 0.787234 (-2715 5480);
FORCEPROP 1 LASTPIN (-2725 5300) $PN 2
J 0
(-2715 5280);
DISPLAY 0.787234 (-2715 5280);
FORCEPROP 2 LAST CDS_LIB pure_quanta
J 0
(-2725 5400);
PAINT MONO (-2725 5400);
DISPLAY INVISIBLE (-2725 5400);
FORCEPROP 1 LAST $LOCATION C273
J 0
(-2675 5600);
DISPLAY 1.021277 (-2675 5600);
DISPLAY INVISIBLE (-2675 5600);
FORCEPROP 2 LAST CDS_LOCATION C273
J 0
(-2675 5600);
DISPLAY 1.021277 (-2675 5600);
DISPLAY INVISIBLE (-2675 5600);
FORCEPROP 2 LAST $SEC 1
J 0
(-2675 5600);
DISPLAY 0.680851 (-2675 5600);
PAINT MONO (-2675 5600);
DISPLAY INVISIBLE (-2675 5600);
FORCEPROP 2 LAST CDS_SEC 1
J 0
(-2675 5600);
DISPLAY 1.021277 (-2675 5600);
DISPLAY INVISIBLE (-2675 5600);
FORCEPROP 1 LAST PATH I91
J 0
(-2675 5550);
DISPLAY 0.978723 (-2675 5550);
PAINT WHITE (-2675 5550);
DISPLAY INVISIBLE (-2675 5550);
FORCEADD UNIVERSAL_POWER..1
(-2725 5675);
FORCEPROP 3 LASTPIN (-2725 5625) SIG_NAME PVCCIN_CPU1\g
J 0
(-2715 5635);
DISPLAY 0.659574 (-2715 5635);
PAINT MONO (-2715 5635);
DISPLAY INVISIBLE (-2715 5635);
FORCEPROP 1 LAST HDL_POWER PVCCIN_CPU1
J 1
(-2525 5725);
DISPLAY 0.872340 (-2525 5725);
PAINT GREEN (-2525 5725);
FORCEPROP 2 LAST CDS_LIB logical_power
J 0
(-2725 5675);
DISPLAY INVISIBLE (-2725 5675);
FORCEPROP 1 LAST PATH I92
J 0
(-2675 5700);
DISPLAY 0.872340 (-2675 5700);
PAINT AQUA (-2675 5700);
DISPLAY INVISIBLE (-2675 5700);
FORCEADD Q_CAP..1
(-3675 6150);
FORCEPROP 1 LAST PART_NUMBER CH6101MEB03
J 0
(-3625 6000);
DISPLAY 0.638298 (-3625 6000);
DISPLAY INVISIBLE (-3625 6000);
FORCEPROP 1 LAST VOLTAGE 6.3V
J 0
(-3625 6150);
DISPLAY 0.638298 (-3625 6150);
FORCEPROP 1 LAST VALUE 10UF
J 0
(-3625 6200);
DISPLAY 0.638298 (-3625 6200);
FORCEPROP 1 LAST TOLERANCE 20%
J 0
(-3625 6100);
DISPLAY 0.638298 (-3625 6100);
FORCEPROP 1 LAST PACK_TYPE C0402
J 0
(-3625 5950);
DISPLAY 0.638298 (-3625 5950);
FORCEPROP 1 LAST MATERIAL X6S
J 0
(-3625 6050);
DISPLAY 0.638298 (-3625 6050);
FORCEPROP 1 LAST $LOCATION C262
J 0
(-3625 6250);
DISPLAY 0.638298 (-3625 6250);
FORCEPROP 1 LASTPIN (-3675 6250) $PN 1
J 0
(-3665 6230);
DISPLAY 0.787234 (-3665 6230);
FORCEPROP 1 LASTPIN (-3675 6050) $PN 2
J 0
(-3665 6030);
DISPLAY 0.787234 (-3665 6030);
FORCEPROP 2 LAST CDS_LIB pure_quanta
J 0
(-3675 6150);
PAINT MONO (-3675 6150);
DISPLAY INVISIBLE (-3675 6150);
FORCEPROP 1 LAST $LOCATION C262
J 0
(-3625 6350);
DISPLAY 1.021277 (-3625 6350);
DISPLAY INVISIBLE (-3625 6350);
FORCEPROP 2 LAST CDS_LOCATION C262
J 0
(-3625 6350);
DISPLAY 1.021277 (-3625 6350);
DISPLAY INVISIBLE (-3625 6350);
FORCEPROP 2 LAST $SEC 1
J 0
(-3625 6350);
DISPLAY 0.680851 (-3625 6350);
PAINT MONO (-3625 6350);
DISPLAY INVISIBLE (-3625 6350);
FORCEPROP 2 LAST CDS_SEC 1
J 0
(-3625 6350);
DISPLAY 1.021277 (-3625 6350);
DISPLAY INVISIBLE (-3625 6350);
FORCEPROP 1 LAST PATH I93
J 0
(-3625 6300);
DISPLAY 0.978723 (-3625 6300);
PAINT WHITE (-3625 6300);
DISPLAY INVISIBLE (-3625 6300);
FORCEADD Q_CAP..1
(-3225 6150);
FORCEPROP 1 LAST PART_NUMBER CH6101MEB03
J 0
(-3175 6000);
DISPLAY 0.638298 (-3175 6000);
DISPLAY INVISIBLE (-3175 6000);
FORCEPROP 1 LAST VOLTAGE 6.3V
J 0
(-3175 6150);
DISPLAY 0.638298 (-3175 6150);
FORCEPROP 1 LAST VALUE 10UF
J 0
(-3175 6200);
DISPLAY 0.638298 (-3175 6200);
FORCEPROP 1 LAST TOLERANCE 20%
J 0
(-3175 6100);
DISPLAY 0.638298 (-3175 6100);
FORCEPROP 1 LAST PACK_TYPE C0402
J 0
(-3175 5950);
DISPLAY 0.638298 (-3175 5950);
FORCEPROP 1 LAST MATERIAL X6S
J 0
(-3175 6050);
DISPLAY 0.638298 (-3175 6050);
FORCEPROP 1 LAST $LOCATION C267
J 0
(-3175 6250);
DISPLAY 0.638298 (-3175 6250);
FORCEPROP 1 LASTPIN (-3225 6250) $PN 1
J 0
(-3215 6230);
DISPLAY 0.787234 (-3215 6230);
FORCEPROP 1 LASTPIN (-3225 6050) $PN 2
J 0
(-3215 6030);
DISPLAY 0.787234 (-3215 6030);
FORCEPROP 2 LAST CDS_LIB pure_quanta
J 0
(-3225 6150);
PAINT MONO (-3225 6150);
DISPLAY INVISIBLE (-3225 6150);
FORCEPROP 1 LAST $LOCATION C267
J 0
(-3175 6350);
DISPLAY 1.021277 (-3175 6350);
DISPLAY INVISIBLE (-3175 6350);
FORCEPROP 2 LAST CDS_LOCATION C267
J 0
(-3175 6350);
DISPLAY 1.021277 (-3175 6350);
DISPLAY INVISIBLE (-3175 6350);
FORCEPROP 2 LAST $SEC 1
J 0
(-3175 6350);
DISPLAY 0.680851 (-3175 6350);
PAINT MONO (-3175 6350);
DISPLAY INVISIBLE (-3175 6350);
FORCEPROP 2 LAST CDS_SEC 1
J 0
(-3175 6350);
DISPLAY 1.021277 (-3175 6350);
DISPLAY INVISIBLE (-3175 6350);
FORCEPROP 1 LAST PATH I94
J 0
(-3175 6300);
DISPLAY 0.978723 (-3175 6300);
PAINT WHITE (-3175 6300);
DISPLAY INVISIBLE (-3175 6300);
FORCEADD Q_CAP..1
(-3675 6925);
FORCEPROP 1 LAST PART_NUMBER CH6101MEB03
J 0
(-3625 6775);
DISPLAY 0.638298 (-3625 6775);
DISPLAY INVISIBLE (-3625 6775);
FORCEPROP 1 LAST VOLTAGE 6.3V
J 0
(-3625 6925);
DISPLAY 0.638298 (-3625 6925);
FORCEPROP 1 LAST TOLERANCE 20%
J 0
(-3625 6875);
DISPLAY 0.638298 (-3625 6875);
FORCEPROP 1 LAST VALUE 10UF
J 0
(-3625 6975);
DISPLAY 0.638298 (-3625 6975);
FORCEPROP 1 LAST PACK_TYPE C0402
J 0
(-3625 6725);
DISPLAY 0.638298 (-3625 6725);
FORCEPROP 1 LAST MATERIAL X6S
J 0
(-3625 6825);
DISPLAY 0.638298 (-3625 6825);
FORCEPROP 1 LAST $LOCATION C261
J 0
(-3625 7025);
DISPLAY 0.638298 (-3625 7025);
FORCEPROP 1 LASTPIN (-3675 7025) $PN 1
J 0
(-3665 7005);
DISPLAY 0.787234 (-3665 7005);
FORCEPROP 1 LASTPIN (-3675 6825) $PN 2
J 0
(-3665 6805);
DISPLAY 0.787234 (-3665 6805);
FORCEPROP 2 LAST CDS_LIB pure_quanta
J 0
(-3675 6925);
PAINT MONO (-3675 6925);
DISPLAY INVISIBLE (-3675 6925);
FORCEPROP 1 LAST $LOCATION C261
J 0
(-3625 7125);
DISPLAY 1.021277 (-3625 7125);
DISPLAY INVISIBLE (-3625 7125);
FORCEPROP 2 LAST CDS_LOCATION C261
J 0
(-3625 7125);
DISPLAY 1.021277 (-3625 7125);
DISPLAY INVISIBLE (-3625 7125);
FORCEPROP 2 LAST $SEC 1
J 0
(-3625 7125);
DISPLAY 0.680851 (-3625 7125);
PAINT MONO (-3625 7125);
DISPLAY INVISIBLE (-3625 7125);
FORCEPROP 2 LAST CDS_SEC 1
J 0
(-3625 7125);
DISPLAY 1.021277 (-3625 7125);
DISPLAY INVISIBLE (-3625 7125);
FORCEPROP 1 LAST PATH I95
J 0
(-3625 7075);
DISPLAY 0.978723 (-3625 7075);
PAINT WHITE (-3625 7075);
DISPLAY INVISIBLE (-3625 7075);
FORCEADD UNIVERSAL_GND..1
(-3225 6575);
FORCEPROP 3 LASTPIN (-3225 6625) SIG_NAME GND\g
J 0
(-3215 6635);
DISPLAY 0.659574 (-3215 6635);
PAINT MONO (-3215 6635);
DISPLAY INVISIBLE (-3215 6635);
FORCEPROP 2 LAST CDS_LIB logical_power
J 0
(-3225 6575);
PAINT MONO (-3225 6575);
DISPLAY INVISIBLE (-3225 6575);
FORCEPROP 1 LAST HDL_POWER GND
J 1
(-3200 6500);
DISPLAY 0.872340 (-3200 6500);
PAINT GREEN (-3200 6500);
DISPLAY INVISIBLE (-3200 6500);
FORCEPROP 1 LAST PATH I96
J 0
(-3150 6575);
DISPLAY 0.872340 (-3150 6575);
PAINT AQUA (-3150 6575);
DISPLAY INVISIBLE (-3150 6575);
FORCEADD Q_CAP..1
(-3225 6925);
FORCEPROP 1 LAST PART_NUMBER CH6101MEB03
J 0
(-3175 6775);
DISPLAY 0.638298 (-3175 6775);
DISPLAY INVISIBLE (-3175 6775);
FORCEPROP 1 LAST VOLTAGE 6.3V
J 0
(-3175 6925);
DISPLAY 0.638298 (-3175 6925);
FORCEPROP 1 LAST TOLERANCE 20%
J 0
(-3175 6875);
DISPLAY 0.638298 (-3175 6875);
FORCEPROP 1 LAST VALUE 10UF
J 0
(-3175 6975);
DISPLAY 0.638298 (-3175 6975);
FORCEPROP 1 LAST PACK_TYPE C0402
J 0
(-3175 6725);
DISPLAY 0.638298 (-3175 6725);
FORCEPROP 1 LAST MATERIAL X6S
J 0
(-3175 6825);
DISPLAY 0.638298 (-3175 6825);
FORCEPROP 1 LAST $LOCATION C266
J 0
(-3175 7025);
DISPLAY 0.638298 (-3175 7025);
FORCEPROP 1 LASTPIN (-3225 7025) $PN 1
J 0
(-3215 7005);
DISPLAY 0.787234 (-3215 7005);
FORCEPROP 1 LASTPIN (-3225 6825) $PN 2
J 0
(-3215 6805);
DISPLAY 0.787234 (-3215 6805);
FORCEPROP 2 LAST CDS_LIB pure_quanta
J 0
(-3225 6925);
PAINT MONO (-3225 6925);
DISPLAY INVISIBLE (-3225 6925);
FORCEPROP 1 LAST $LOCATION C266
J 0
(-3175 7125);
DISPLAY 1.021277 (-3175 7125);
DISPLAY INVISIBLE (-3175 7125);
FORCEPROP 2 LAST CDS_LOCATION C266
J 0
(-3175 7125);
DISPLAY 1.021277 (-3175 7125);
DISPLAY INVISIBLE (-3175 7125);
FORCEPROP 2 LAST $SEC 1
J 0
(-3175 7125);
DISPLAY 0.680851 (-3175 7125);
PAINT MONO (-3175 7125);
DISPLAY INVISIBLE (-3175 7125);
FORCEPROP 2 LAST CDS_SEC 1
J 0
(-3175 7125);
DISPLAY 1.021277 (-3175 7125);
DISPLAY INVISIBLE (-3175 7125);
FORCEPROP 1 LAST PATH I97
J 0
(-3175 7075);
DISPLAY 0.978723 (-3175 7075);
PAINT WHITE (-3175 7075);
DISPLAY INVISIBLE (-3175 7075);
FORCEADD Q_CAP..1
(-2750 6150);
FORCEPROP 1 LAST PART_NUMBER CH622KMEB01
J 0
(-2700 6000);
DISPLAY 0.638298 (-2700 6000);
DISPLAY INVISIBLE (-2700 6000);
FORCEPROP 1 LAST TOLERANCE 20%
J 0
(-2700 6100);
DISPLAY 0.638298 (-2700 6100);
FORCEPROP 1 LAST VOLTAGE 4V
J 0
(-2700 6150);
DISPLAY 0.638298 (-2700 6150);
FORCEPROP 1 LAST VALUE 22UF
J 0
(-2700 6200);
DISPLAY 0.638298 (-2700 6200);
FORCEPROP 1 LAST PACK_TYPE C0402
J 0
(-2700 5950);
DISPLAY 0.638298 (-2700 5950);
FORCEPROP 1 LAST MATERIAL X6S
J 0
(-2700 6050);
DISPLAY 0.638298 (-2700 6050);
FORCEPROP 1 LAST $LOCATION C272
J 0
(-2700 6250);
DISPLAY 0.638298 (-2700 6250);
FORCEPROP 1 LASTPIN (-2750 6250) $PN 1
J 0
(-2740 6230);
DISPLAY 0.787234 (-2740 6230);
FORCEPROP 1 LASTPIN (-2750 6050) $PN 2
J 0
(-2740 6030);
DISPLAY 0.787234 (-2740 6030);
FORCEPROP 2 LAST CDS_LIB pure_quanta
J 0
(-2750 6150);
PAINT MONO (-2750 6150);
DISPLAY INVISIBLE (-2750 6150);
FORCEPROP 1 LAST $LOCATION C272
J 0
(-2700 6350);
DISPLAY 1.021277 (-2700 6350);
DISPLAY INVISIBLE (-2700 6350);
FORCEPROP 2 LAST CDS_LOCATION C272
J 0
(-2700 6350);
DISPLAY 1.021277 (-2700 6350);
DISPLAY INVISIBLE (-2700 6350);
FORCEPROP 2 LAST $SEC 1
J 0
(-2700 6350);
DISPLAY 0.680851 (-2700 6350);
PAINT MONO (-2700 6350);
DISPLAY INVISIBLE (-2700 6350);
FORCEPROP 2 LAST CDS_SEC 1
J 0
(-2700 6350);
DISPLAY 1.021277 (-2700 6350);
DISPLAY INVISIBLE (-2700 6350);
FORCEPROP 1 LAST PATH I98
J 0
(-2700 6300);
DISPLAY 0.978723 (-2700 6300);
PAINT WHITE (-2700 6300);
DISPLAY INVISIBLE (-2700 6300);
FORCEADD UNIVERSAL_POWER..1
(-2750 6425);
FORCEPROP 3 LASTPIN (-2750 6375) SIG_NAME PVCCIN_CPU1\g
J 0
(-2740 6385);
DISPLAY 0.659574 (-2740 6385);
PAINT MONO (-2740 6385);
DISPLAY INVISIBLE (-2740 6385);
FORCEPROP 1 LAST HDL_POWER PVCCIN_CPU1
J 1
(-2550 6475);
DISPLAY 0.872340 (-2550 6475);
PAINT GREEN (-2550 6475);
FORCEPROP 2 LAST CDS_LIB logical_power
J 0
(-2750 6425);
DISPLAY INVISIBLE (-2750 6425);
FORCEPROP 1 LAST PATH I99
J 0
(-2700 6450);
DISPLAY 0.872340 (-2700 6450);
PAINT AQUA (-2700 6450);
DISPLAY INVISIBLE (-2700 6450);
FORCEADD QUANTA_TITLE_BLOCK_C..1
(1825 1125);
FORCEPROP 0 LAST CDS_CON_LAST_MODIFIED Fri Aug 25 14:00:57 2023
J 0
(-60 1140);
PAINT MONO (-60 1140);
DISPLAY INVISIBLE (-60 1140);
FORCEPROP 1 LAST CUSTOM_TXT_CDS <CON_LAST_MODIFIED>
J 0
(-60 1140);
DISPLAY 0.978723 (-60 1140);
FORCEPROP 2 LAST CUSTOM_TXT_CDS <XR_PAGE_TITLE>
J 0
(-6065 6375);
DISPLAY 0.638298 (-6065 6375);
PAINT PINK (-6065 6375);
DISPLAY INVISIBLE (-6065 6375);
FORCEPROP 2 LAST CUSTOM_TXT_CDS <CON_PAGE_NUM> OF <CON_TOTAL_PAGES>
J 0
(1375 1150);
DISPLAY 0.978723 (1375 1150);
FORCEPROP 2 LAST CUSTOM_TXT_CDS <Q_NUMBER>
J 0
(422 1228);
DISPLAY 1.212766 (422 1228);
FORCEPROP 2 LAST CUSTOM_TXT_CDS <Q_REV>
J 0
(1641 1228);
DISPLAY 1.212766 (1641 1228);
FORCEPROP 2 LAST CUSTOM_TXT_CDS <NAME_2>
J 0
(-1350 1175);
FORCEPROP 2 LAST CUSTOM_TXT_CDS <NAME_1>
J 0
(-1350 1300);
FORCEPROP 2 LAST CUSTOM_TXT_CDS <Q_PROJ>
J 0
(-557 1227);
DISPLAY 1.212766 (-557 1227);
FORCEPROP 1 LAST Q_TITLE SPR CPU1 TOP DECOUPLING CAPS
J 0
(-7516 1151);
DISPLAY 1.957447 (-7516 1151);
PAINT GREEN (-7516 1151);
FORCEPROP 1 LAST Q_DEPT 
J 1
(-1938 1174);
DISPLAY 1.957447 (-1938 1174);
PAINT GREEN (-1938 1174);
FORCEPROP 1 LAST COMMENT_BODY TRUE
J 0
(1837 1112);
DISPLAY 0.978723 (1837 1112);
PAINT GREEN (1837 1112);
DISPLAY INVISIBLE (1837 1112);
FORCEPROP 2 LAST CDS_XR_PAGE_TITLE CR-77 : @S9S_MB_2U_LIB.S9S_MB_2U(SCH_1):PAGE77
J 0
(-6065 6375);
DISPLAY 0.638298 (-6065 6375);
PAINT PINK (-6065 6375);
DISPLAY INVISIBLE (-6065 6375);
FORCEPROP 2 LAST PAGE_BORDER TRUE
J 0
(-6065 6375);
DISPLAY 0.638298 (-6065 6375);
PAINT PINK (-6065 6375);
DISPLAY INVISIBLE (-6065 6375);
FORCEPROP 1 LAST CDS_LMAN_SYM_OUTLINE -9475,6775,100,-125
J 0
(1825 1125);
DISPLAY 0.468085 (1825 1125);
PAINT GREEN (1825 1125);
DISPLAY INVISIBLE (1825 1125);
FORCEPROP 2 LAST CDS_LIB pure_quanta
J 0
(1825 1125);
PAINT MONO (1825 1125);
DISPLAY INVISIBLE (1825 1125);
WIRE 16 -1 (-7250 2400)(-7250 2450);
WIRE 16 -1 (-6800 2400)(-7250 2400);
WIRE 16 -1 (-7250 2400)(-7250 2325);
WIRE 16 -1 (-7250 3225)(-7250 3275);
WIRE 16 -1 (-6800 3225)(-7250 3225);
WIRE 16 -1 (-7250 3225)(-7250 3150);
WIRE 16 -1 (-7250 4025)(-7250 4075);
WIRE 16 -1 (-6800 4025)(-7250 4025);
WIRE 16 -1 (-7250 4025)(-7250 3950);
WIRE 16 -1 (-7250 4800)(-7250 4850);
WIRE 16 -1 (-6800 4800)(-7250 4800);
WIRE 16 -1 (-7250 4800)(-7250 4725);
WIRE 16 -1 (-7250 5575)(-7250 5625);
WIRE 16 -1 (-6800 5575)(-7250 5575);
WIRE 16 -1 (-7250 5575)(-7250 5500);
WIRE 16 -1 (-7275 6325)(-7275 6375);
WIRE 16 -1 (-6825 6325)(-7275 6325);
WIRE 16 -1 (-7275 6325)(-7275 6250);
WIRE 16 -1 (-7275 7100)(-7275 7150);
WIRE 16 -1 (-6825 7100)(-7275 7100);
WIRE 16 -1 (-7275 7100)(-7275 7025);
WIRE 16 -1 (-5000 3225)(-5000 3275);
WIRE 16 -1 (-4550 3225)(-5000 3225);
WIRE 16 -1 (-5000 3225)(-5000 3150);
WIRE 16 -1 (-1975 3225)(-1975 3275);
WIRE 16 -1 (-1525 3225)(-1975 3225);
WIRE 16 -1 (-1975 3225)(-1975 3150);
WIRE 16 -1 (-1975 4000)(-1975 3875);
WIRE 16 -1 (-2725 4800)(-2725 4850);
WIRE 16 -1 (-2275 4800)(-2725 4800);
WIRE 16 -1 (-2725 4800)(-2725 4725);
WIRE 16 -1 (-2725 5575)(-2725 5625);
WIRE 16 -1 (-2275 5575)(-2725 5575);
WIRE 16 -1 (-2725 5575)(-2725 5500);
WIRE 16 -1 (-2750 6325)(-2750 6375);
WIRE 16 -1 (-2300 6325)(-2750 6325);
WIRE 16 -1 (-2750 6325)(-2750 6250);
WIRE 16 -1 (-2750 7100)(-2750 7150);
WIRE 16 -1 (-2300 7100)(-2750 7100);
WIRE 16 -1 (-2750 7100)(-2750 7025);
WIRE 16 -1 (-5900 2775)(-5900 2825);
WIRE 16 -1 (-3200 2750)(-3200 2825);
WIRE 16 -1 (-2750 1925)(-2750 2000);
WIRE 16 -1 (-3200 3550)(-3200 3625);
WIRE 16 -1 (-3200 4325)(-3200 4400);
WIRE 16 -1 (-1975 3550)(-1975 3675);
WIRE 16 -1 (-3225 5850)(-3225 5925);
WIRE 16 -1 (-3200 5100)(-3200 5175);
WIRE 16 -1 (-3225 6625)(-3225 6700);
WIRE 16 -1 (-625 2775)(-625 2825);
WIRE 16 -1 (875 4325)(875 4400);
WIRE 16 -1 (1325 5100)(1325 5175);
WIRE 16 -1 (1300 5850)(1300 5925);
WIRE 16 -1 (1300 6625)(1300 6700);
WIRE 16 -1 (-1525 3150)(-1525 3225);
WIRE 16 -1 (-1075 3225)(-1525 3225);
WIRE 16 -1 (-1075 3225)(-1075 3150);
WIRE 16 -1 (-625 3225)(-1075 3225);
WIRE 16 -1 (-625 3150)(-625 3225);
WIRE 16 -1 (-3200 4725)(-3200 4800);
WIRE 16 -1 (-3650 4800)(-3650 4725);
WIRE 16 -1 (-3200 4800)(-3650 4800);
WIRE 16 -1 (-4100 4725)(-4100 4800);
WIRE 16 -1 (-3650 4800)(-4100 4800);
WIRE 16 -1 (-4550 4725)(-4550 4800);
WIRE 16 -1 (-4100 4800)(-4550 4800);
WIRE 16 -1 (-5000 4800)(-5000 4725);
WIRE 16 -1 (-4550 4800)(-5000 4800);
WIRE 16 -1 (-5450 4725)(-5450 4800);
WIRE 16 -1 (-5000 4800)(-5450 4800);
WIRE 16 -1 (-5900 4725)(-5900 4800);
WIRE 16 -1 (-5450 4800)(-5900 4800);
WIRE 16 -1 (-6350 4800)(-6350 4725);
WIRE 16 -1 (-5900 4800)(-6350 4800);
WIRE 16 -1 (-6350 4800)(-6800 4800);
WIRE 16 -1 (-6800 4725)(-6800 4800);
WIRE 16 -1 (-3200 5175)(-3200 5300);
WIRE 16 -1 (-3650 5175)(-3650 5300);
WIRE 16 -1 (-3200 5175)(-3650 5175);
WIRE 16 -1 (-4100 5175)(-4100 5300);
WIRE 16 -1 (-3650 5175)(-4100 5175);
WIRE 16 -1 (-7250 5175)(-7250 5300);
WIRE 16 -1 (-6800 5175)(-7250 5175);
WIRE 16 -1 (-6800 5175)(-6800 5300);
WIRE 16 -1 (-4550 5175)(-4550 5300);
WIRE 16 -1 (-4100 5175)(-4550 5175);
WIRE 16 -1 (-5000 5175)(-5000 5300);
WIRE 16 -1 (-4550 5175)(-5000 5175);
WIRE 16 -1 (-6350 5175)(-6800 5175);
WIRE 16 -1 (-6350 5175)(-6350 5300);
WIRE 16 -1 (-5900 5175)(-6350 5175);
WIRE 16 -1 (-5900 5175)(-5900 5300);
WIRE 16 -1 (-5450 5175)(-5450 5300);
WIRE 16 -1 (-5000 5175)(-5450 5175);
WIRE 16 -1 (-5450 5175)(-5900 5175);
WIRE 16 -1 (-6800 3150)(-6800 3225);
WIRE 16 -1 (-6350 3225)(-6800 3225);
WIRE 16 -1 (-6350 3225)(-6350 3150);
WIRE 16 -1 (-5900 3225)(-6350 3225);
WIRE 16 -1 (-5900 3150)(-5900 3225);
WIRE 16 -1 (-3225 6250)(-3225 6325);
WIRE 16 -1 (-3675 6325)(-3675 6250);
WIRE 16 -1 (-3225 6325)(-3675 6325);
WIRE 16 -1 (-4125 6250)(-4125 6325);
WIRE 16 -1 (-3675 6325)(-4125 6325);
WIRE 16 -1 (-4575 6250)(-4575 6325);
WIRE 16 -1 (-4125 6325)(-4575 6325);
WIRE 16 -1 (-5025 6325)(-5025 6250);
WIRE 16 -1 (-4575 6325)(-5025 6325);
WIRE 16 -1 (-5475 6250)(-5475 6325);
WIRE 16 -1 (-5025 6325)(-5475 6325);
WIRE 16 -1 (-5925 6250)(-5925 6325);
WIRE 16 -1 (-5475 6325)(-5925 6325);
WIRE 16 -1 (-6375 6325)(-6375 6250);
WIRE 16 -1 (-5925 6325)(-6375 6325);
WIRE 16 -1 (-6375 6325)(-6825 6325);
WIRE 16 -1 (-6825 6250)(-6825 6325);
WIRE 16 -1 (1300 7025)(1300 7100);
WIRE 16 -1 (850 7100)(850 7025);
WIRE 16 -1 (1300 7100)(850 7100);
WIRE 16 -1 (400 7025)(400 7100);
WIRE 16 -1 (850 7100)(400 7100);
WIRE 16 -1 (-50 7025)(-50 7100);
WIRE 16 -1 (400 7100)(-50 7100);
WIRE 16 -1 (-500 7100)(-500 7025);
WIRE 16 -1 (-50 7100)(-500 7100);
WIRE 16 -1 (-950 7025)(-950 7100);
WIRE 16 -1 (-500 7100)(-950 7100);
WIRE 16 -1 (-1400 7025)(-1400 7100);
WIRE 16 -1 (-950 7100)(-1400 7100);
WIRE 16 -1 (-1850 7100)(-1850 7025);
WIRE 16 -1 (-1400 7100)(-1850 7100);
WIRE 16 -1 (-1850 7100)(-2300 7100);
WIRE 16 -1 (-2300 7025)(-2300 7100);
WIRE 16 -1 (1300 5925)(1300 6050);
WIRE 16 -1 (850 5925)(850 6050);
WIRE 16 -1 (1300 5925)(850 5925);
WIRE 16 -1 (400 5925)(400 6050);
WIRE 16 -1 (850 5925)(400 5925);
WIRE 16 -1 (-2750 5925)(-2750 6050);
WIRE 16 -1 (-2300 5925)(-2750 5925);
WIRE 16 -1 (-2300 5925)(-2300 6050);
WIRE 16 -1 (-50 5925)(-50 6050);
WIRE 16 -1 (400 5925)(-50 5925);
WIRE 16 -1 (-500 5925)(-500 6050);
WIRE 16 -1 (-50 5925)(-500 5925);
WIRE 16 -1 (-1850 5925)(-2300 5925);
WIRE 16 -1 (-1850 5925)(-1850 6050);
WIRE 16 -1 (-1400 5925)(-1850 5925);
WIRE 16 -1 (-1400 5925)(-1400 6050);
WIRE 16 -1 (-950 5925)(-950 6050);
WIRE 16 -1 (-500 5925)(-950 5925);
WIRE 16 -1 (-950 5925)(-1400 5925);
WIRE 16 -1 (1300 6250)(1300 6325);
WIRE 16 -1 (850 6325)(850 6250);
WIRE 16 -1 (1300 6325)(850 6325);
WIRE 16 -1 (400 6250)(400 6325);
WIRE 16 -1 (850 6325)(400 6325);
WIRE 16 -1 (-50 6250)(-50 6325);
WIRE 16 -1 (400 6325)(-50 6325);
WIRE 16 -1 (-500 6325)(-500 6250);
WIRE 16 -1 (-50 6325)(-500 6325);
WIRE 16 -1 (-950 6250)(-950 6325);
WIRE 16 -1 (-500 6325)(-950 6325);
WIRE 16 -1 (-1400 6250)(-1400 6325);
WIRE 16 -1 (-950 6325)(-1400 6325);
WIRE 16 -1 (-1850 6325)(-1850 6250);
WIRE 16 -1 (-1400 6325)(-1850 6325);
WIRE 16 -1 (-1850 6325)(-2300 6325);
WIRE 16 -1 (-2300 6250)(-2300 6325);
WIRE 16 -1 (1300 6700)(1300 6825);
WIRE 16 -1 (850 6700)(850 6825);
WIRE 16 -1 (1300 6700)(850 6700);
WIRE 16 -1 (400 6700)(400 6825);
WIRE 16 -1 (850 6700)(400 6700);
WIRE 16 -1 (-2750 6700)(-2750 6825);
WIRE 16 -1 (-2300 6700)(-2750 6700);
WIRE 16 -1 (-2300 6700)(-2300 6825);
WIRE 16 -1 (-50 6700)(-50 6825);
WIRE 16 -1 (400 6700)(-50 6700);
WIRE 16 -1 (-500 6700)(-500 6825);
WIRE 16 -1 (-50 6700)(-500 6700);
WIRE 16 -1 (-1850 6700)(-2300 6700);
WIRE 16 -1 (-1850 6700)(-1850 6825);
WIRE 16 -1 (-1400 6700)(-1850 6700);
WIRE 16 -1 (-1400 6700)(-1400 6825);
WIRE 16 -1 (-950 6700)(-950 6825);
WIRE 16 -1 (-500 6700)(-950 6700);
WIRE 16 -1 (-950 6700)(-1400 6700);
WIRE 16 -1 (1325 5175)(1325 5300);
WIRE 16 -1 (875 5175)(875 5300);
WIRE 16 -1 (1325 5175)(875 5175);
WIRE 16 -1 (425 5175)(425 5300);
WIRE 16 -1 (875 5175)(425 5175);
WIRE 16 -1 (-2725 5175)(-2725 5300);
WIRE 16 -1 (-2275 5175)(-2725 5175);
WIRE 16 -1 (-2275 5175)(-2275 5300);
WIRE 16 -1 (-25 5175)(-25 5300);
WIRE 16 -1 (425 5175)(-25 5175);
WIRE 16 -1 (-475 5175)(-475 5300);
WIRE 16 -1 (-25 5175)(-475 5175);
WIRE 16 -1 (-1825 5175)(-2275 5175);
WIRE 16 -1 (-1825 5175)(-1825 5300);
WIRE 16 -1 (-1375 5175)(-1825 5175);
WIRE 16 -1 (-1375 5175)(-1375 5300);
WIRE 16 -1 (-925 5175)(-925 5300);
WIRE 16 -1 (-475 5175)(-925 5175);
WIRE 16 -1 (-925 5175)(-1375 5175);
WIRE 16 -1 (1325 5500)(1325 5575);
WIRE 16 -1 (875 5575)(875 5500);
WIRE 16 -1 (1325 5575)(875 5575);
WIRE 16 -1 (425 5500)(425 5575);
WIRE 16 -1 (875 5575)(425 5575);
WIRE 16 -1 (-25 5500)(-25 5575);
WIRE 16 -1 (425 5575)(-25 5575);
WIRE 16 -1 (-475 5575)(-475 5500);
WIRE 16 -1 (-25 5575)(-475 5575);
WIRE 16 -1 (-925 5500)(-925 5575);
WIRE 16 -1 (-475 5575)(-925 5575);
WIRE 16 -1 (-1375 5500)(-1375 5575);
WIRE 16 -1 (-925 5575)(-1375 5575);
WIRE 16 -1 (-1825 5575)(-1825 5500);
WIRE 16 -1 (-1375 5575)(-1825 5575);
WIRE 16 -1 (-1825 5575)(-2275 5575);
WIRE 16 -1 (-2275 5500)(-2275 5575);
WIRE 16 -1 (875 4800)(875 4725);
WIRE 16 -1 (425 4725)(425 4800);
WIRE 16 -1 (875 4800)(425 4800);
WIRE 16 -1 (-25 4725)(-25 4800);
WIRE 16 -1 (425 4800)(-25 4800);
WIRE 16 -1 (-475 4800)(-475 4725);
WIRE 16 -1 (-25 4800)(-475 4800);
WIRE 16 -1 (-925 4725)(-925 4800);
WIRE 16 -1 (-475 4800)(-925 4800);
WIRE 16 -1 (-1375 4725)(-1375 4800);
WIRE 16 -1 (-925 4800)(-1375 4800);
WIRE 16 -1 (-1825 4800)(-1825 4725);
WIRE 16 -1 (-1375 4800)(-1825 4800);
WIRE 16 -1 (-1825 4800)(-2275 4800);
WIRE 16 -1 (-2275 4725)(-2275 4800);
WIRE 16 -1 (875 4400)(875 4525);
WIRE 16 -1 (425 4400)(425 4525);
WIRE 16 -1 (875 4400)(425 4400);
WIRE 16 -1 (-2725 4400)(-2725 4525);
WIRE 16 -1 (-2275 4400)(-2725 4400);
WIRE 16 -1 (-2275 4400)(-2275 4525);
WIRE 16 -1 (-25 4400)(-25 4525);
WIRE 16 -1 (425 4400)(-25 4400);
WIRE 16 -1 (-475 4400)(-475 4525);
WIRE 16 -1 (-25 4400)(-475 4400);
WIRE 16 -1 (-1825 4400)(-2275 4400);
WIRE 16 -1 (-1825 4400)(-1825 4525);
WIRE 16 -1 (-1375 4400)(-1825 4400);
WIRE 16 -1 (-1375 4400)(-1375 4525);
WIRE 16 -1 (-925 4400)(-925 4525);
WIRE 16 -1 (-475 4400)(-925 4400);
WIRE 16 -1 (-925 4400)(-1375 4400);
WIRE 16 -1 (-1975 2825)(-1975 2950);
WIRE 16 -1 (-1525 2825)(-1975 2825);
WIRE 16 -1 (-1525 2825)(-1525 2950);
WIRE 16 -1 (-1075 2825)(-1525 2825);
WIRE 16 -1 (-1075 2825)(-1075 2950);
WIRE 16 -1 (-625 2825)(-1075 2825);
WIRE 16 -1 (-625 2950)(-625 2825);
WIRE 16 -1 (-3225 7025)(-3225 7100);
WIRE 16 -1 (-3675 7100)(-3675 7025);
WIRE 16 -1 (-3225 7100)(-3675 7100);
WIRE 16 -1 (-4125 7025)(-4125 7100);
WIRE 16 -1 (-3675 7100)(-4125 7100);
WIRE 16 -1 (-4575 7025)(-4575 7100);
WIRE 16 -1 (-4125 7100)(-4575 7100);
WIRE 16 -1 (-5025 7100)(-5025 7025);
WIRE 16 -1 (-4575 7100)(-5025 7100);
WIRE 16 -1 (-5475 7025)(-5475 7100);
WIRE 16 -1 (-5025 7100)(-5475 7100);
WIRE 16 -1 (-5925 7025)(-5925 7100);
WIRE 16 -1 (-5475 7100)(-5925 7100);
WIRE 16 -1 (-6375 7100)(-6375 7025);
WIRE 16 -1 (-5925 7100)(-6375 7100);
WIRE 16 -1 (-6375 7100)(-6825 7100);
WIRE 16 -1 (-6825 7025)(-6825 7100);
WIRE 16 -1 (-3225 6700)(-3225 6825);
WIRE 16 -1 (-3675 6700)(-3675 6825);
WIRE 16 -1 (-3225 6700)(-3675 6700);
WIRE 16 -1 (-4125 6700)(-4125 6825);
WIRE 16 -1 (-3675 6700)(-4125 6700);
WIRE 16 -1 (-7275 6700)(-7275 6825);
WIRE 16 -1 (-6825 6700)(-7275 6700);
WIRE 16 -1 (-6825 6700)(-6825 6825);
WIRE 16 -1 (-4575 6700)(-4575 6825);
WIRE 16 -1 (-4125 6700)(-4575 6700);
FORCEPROP 0 LAST VOLTAGE 0
J 0
(-4350 6700);
DISPLAY INVISIBLE (-4350 6700);
WIRE 16 -1 (-5025 6700)(-5025 6825);
WIRE 16 -1 (-4575 6700)(-5025 6700);
WIRE 16 -1 (-6375 6700)(-6825 6700);
WIRE 16 -1 (-6375 6700)(-6375 6825);
WIRE 16 -1 (-5925 6700)(-6375 6700);
WIRE 16 -1 (-5925 6700)(-5925 6825);
WIRE 16 -1 (-5475 6700)(-5475 6825);
WIRE 16 -1 (-5025 6700)(-5475 6700);
WIRE 16 -1 (-5475 6700)(-5925 6700);
WIRE 16 -1 (-3225 5925)(-3225 6050);
WIRE 16 -1 (-3675 5925)(-3675 6050);
WIRE 16 -1 (-3225 5925)(-3675 5925);
WIRE 16 -1 (-4125 5925)(-4125 6050);
WIRE 16 -1 (-3675 5925)(-4125 5925);
WIRE 16 -1 (-7275 5925)(-7275 6050);
WIRE 16 -1 (-6825 5925)(-7275 5925);
WIRE 16 -1 (-6825 5925)(-6825 6050);
WIRE 16 -1 (-4575 5925)(-4575 6050);
WIRE 16 -1 (-4125 5925)(-4575 5925);
WIRE 16 -1 (-5025 5925)(-5025 6050);
WIRE 16 -1 (-4575 5925)(-5025 5925);
WIRE 16 -1 (-6375 5925)(-6825 5925);
WIRE 16 -1 (-6375 5925)(-6375 6050);
WIRE 16 -1 (-5925 5925)(-6375 5925);
WIRE 16 -1 (-5925 5925)(-5925 6050);
WIRE 16 -1 (-5475 5925)(-5475 6050);
WIRE 16 -1 (-5025 5925)(-5475 5925);
WIRE 16 -1 (-5475 5925)(-5925 5925);
WIRE 16 -1 (-3200 5500)(-3200 5575);
WIRE 16 -1 (-3650 5575)(-3650 5500);
WIRE 16 -1 (-3200 5575)(-3650 5575);
WIRE 16 -1 (-4100 5500)(-4100 5575);
WIRE 16 -1 (-3650 5575)(-4100 5575);
WIRE 16 -1 (-4550 5500)(-4550 5575);
WIRE 16 -1 (-4100 5575)(-4550 5575);
WIRE 16 -1 (-5000 5575)(-5000 5500);
WIRE 16 -1 (-4550 5575)(-5000 5575);
WIRE 16 -1 (-5450 5500)(-5450 5575);
WIRE 16 -1 (-5000 5575)(-5450 5575);
WIRE 16 -1 (-5900 5500)(-5900 5575);
WIRE 16 -1 (-5450 5575)(-5900 5575);
WIRE 16 -1 (-6350 5575)(-6350 5500);
WIRE 16 -1 (-5900 5575)(-6350 5575);
WIRE 16 -1 (-6350 5575)(-6800 5575);
WIRE 16 -1 (-6800 5500)(-6800 5575);
WIRE 16 -1 (-3200 4400)(-3200 4525);
WIRE 16 -1 (-3650 4400)(-3650 4525);
WIRE 16 -1 (-3200 4400)(-3650 4400);
WIRE 16 -1 (-4100 4400)(-4100 4525);
WIRE 16 -1 (-3650 4400)(-4100 4400);
WIRE 16 -1 (-7250 4400)(-7250 4525);
WIRE 16 -1 (-6800 4400)(-7250 4400);
WIRE 16 -1 (-6800 4400)(-6800 4525);
WIRE 16 -1 (-4550 4400)(-4550 4525);
WIRE 16 -1 (-4100 4400)(-4550 4400);
WIRE 16 -1 (-5000 4400)(-5000 4525);
WIRE 16 -1 (-4550 4400)(-5000 4400);
WIRE 16 -1 (-6350 4400)(-6800 4400);
WIRE 16 -1 (-6350 4400)(-6350 4525);
WIRE 16 -1 (-5900 4400)(-6350 4400);
WIRE 16 -1 (-5900 4400)(-5900 4525);
WIRE 16 -1 (-5450 4400)(-5450 4525);
WIRE 16 -1 (-5000 4400)(-5450 4400);
WIRE 16 -1 (-5450 4400)(-5900 4400);
WIRE 16 -1 (-3200 3950)(-3200 4025);
WIRE 16 -1 (-3650 4025)(-3650 3950);
WIRE 16 -1 (-3200 4025)(-3650 4025);
WIRE 16 -1 (-4100 3950)(-4100 4025);
WIRE 16 -1 (-3650 4025)(-4100 4025);
WIRE 16 -1 (-4550 3950)(-4550 4025);
WIRE 16 -1 (-4100 4025)(-4550 4025);
WIRE 16 -1 (-5000 4025)(-5000 3950);
WIRE 16 -1 (-4550 4025)(-5000 4025);
WIRE 16 -1 (-5450 3950)(-5450 4025);
WIRE 16 -1 (-5000 4025)(-5450 4025);
WIRE 16 -1 (-5900 3950)(-5900 4025);
WIRE 16 -1 (-5450 4025)(-5900 4025);
WIRE 16 -1 (-6350 4025)(-6350 3950);
WIRE 16 -1 (-5900 4025)(-6350 4025);
WIRE 16 -1 (-6350 4025)(-6800 4025);
WIRE 16 -1 (-6800 3950)(-6800 4025);
WIRE 16 -1 (-3200 3625)(-3200 3750);
WIRE 16 -1 (-3650 3625)(-3650 3750);
WIRE 16 -1 (-3200 3625)(-3650 3625);
WIRE 16 -1 (-4100 3625)(-4100 3750);
WIRE 16 -1 (-3650 3625)(-4100 3625);
WIRE 16 -1 (-7250 3625)(-7250 3750);
WIRE 16 -1 (-6800 3625)(-7250 3625);
WIRE 16 -1 (-6800 3625)(-6800 3750);
WIRE 16 -1 (-4550 3625)(-4550 3750);
WIRE 16 -1 (-4100 3625)(-4550 3625);
WIRE 16 -1 (-5000 3625)(-5000 3750);
WIRE 16 -1 (-4550 3625)(-5000 3625);
WIRE 16 -1 (-6350 3625)(-6800 3625);
WIRE 16 -1 (-6350 3625)(-6350 3750);
WIRE 16 -1 (-5900 3625)(-6350 3625);
WIRE 16 -1 (-5900 3625)(-5900 3750);
WIRE 16 -1 (-5450 3625)(-5450 3750);
WIRE 16 -1 (-5000 3625)(-5450 3625);
WIRE 16 -1 (-5450 3625)(-5900 3625);
WIRE 16 -1 (-4550 3150)(-4550 3225);
WIRE 16 -1 (-4100 3225)(-4550 3225);
WIRE 16 -1 (-4100 3150)(-4100 3225);
WIRE 16 -1 (-3650 3225)(-4100 3225);
WIRE 16 -1 (-3650 3225)(-3650 3150);
WIRE 16 -1 (-3200 3225)(-3650 3225);
WIRE 16 -1 (-3200 3150)(-3200 3225);
WIRE 16 -1 (-5000 2825)(-5000 2950);
WIRE 16 -1 (-4550 2825)(-5000 2825);
WIRE 16 -1 (-4550 2825)(-4550 2950);
WIRE 16 -1 (-4100 2825)(-4550 2825);
WIRE 16 -1 (-4100 2825)(-4100 2950);
WIRE 16 -1 (-3650 2825)(-4100 2825);
WIRE 16 -1 (-3650 2825)(-3650 2950);
WIRE 16 -1 (-3200 2825)(-3200 2950);
WIRE 16 -1 (-3200 2825)(-3650 2825);
WIRE 16 -1 (-2750 2325)(-2750 2400);
WIRE 16 -1 (-3200 2325)(-3200 2400);
WIRE 16 -1 (-2750 2400)(-3200 2400);
WIRE 16 -1 (-3650 2400)(-3650 2325);
WIRE 16 -1 (-3200 2400)(-3650 2400);
WIRE 16 -1 (-4100 2325)(-4100 2400);
WIRE 16 -1 (-3650 2400)(-4100 2400);
WIRE 16 -1 (-4550 2325)(-4550 2400);
WIRE 16 -1 (-4100 2400)(-4550 2400);
WIRE 16 -1 (-5000 2400)(-5000 2325);
WIRE 16 -1 (-4550 2400)(-5000 2400);
WIRE 16 -1 (-5450 2325)(-5450 2400);
WIRE 16 -1 (-5000 2400)(-5450 2400);
WIRE 16 -1 (-5900 2325)(-5900 2400);
WIRE 16 -1 (-5450 2400)(-5900 2400);
WIRE 16 -1 (-6350 2400)(-6350 2325);
WIRE 16 -1 (-5900 2400)(-6350 2400);
WIRE 16 -1 (-6350 2400)(-6800 2400);
WIRE 16 -1 (-6800 2325)(-6800 2400);
WIRE 16 -1 (-7250 2000)(-7250 2125);
WIRE 16 -1 (-6800 2000)(-7250 2000);
WIRE 16 -1 (-6800 2000)(-6800 2125);
WIRE 16 -1 (-6350 2000)(-6800 2000);
WIRE 16 -1 (-6350 2000)(-6350 2125);
WIRE 16 -1 (-5900 2000)(-6350 2000);
WIRE 16 -1 (-5900 2000)(-5900 2125);
WIRE 16 -1 (-5450 2000)(-5900 2000);
WIRE 16 -1 (-5450 2000)(-5450 2125);
WIRE 16 -1 (-5000 2000)(-5450 2000);
WIRE 16 -1 (-5000 2000)(-5000 2125);
WIRE 16 -1 (-4550 2000)(-5000 2000);
WIRE 16 -1 (-4550 2000)(-4550 2125);
WIRE 16 -1 (-4100 2000)(-4550 2000);
WIRE 16 -1 (-4100 2000)(-4100 2125);
WIRE 16 -1 (-3650 2000)(-4100 2000);
WIRE 16 -1 (-3650 2000)(-3650 2125);
WIRE 16 -1 (-3200 2000)(-3650 2000);
WIRE 16 -1 (-3200 2000)(-3200 2125);
WIRE 16 -1 (-2750 2000)(-3200 2000);
WIRE 16 -1 (-2750 2000)(-2750 2125);
WIRE 16 -1 (-7250 2825)(-7250 2950);
WIRE 16 -1 (-6800 2825)(-7250 2825);
WIRE 16 -1 (-6800 2825)(-6800 2950);
WIRE 16 -1 (-6350 2825)(-6800 2825);
WIRE 16 -1 (-6350 2825)(-6350 2950);
WIRE 16 -1 (-5900 2825)(-6350 2825);
WIRE 16 -1 (-5900 2950)(-5900 2825);
DOT 1 (-5900 2000);
DOT 1 (850 7100);
DOT 1 (400 7100);
DOT 1 (1300 6700);
DOT 1 (1300 5925);
DOT 1 (850 6700);
DOT 1 (400 6700);
DOT 1 (850 6325);
DOT 1 (850 5925);
DOT 1 (400 6325);
DOT 1 (400 5925);
DOT 1 (1325 5175);
DOT 1 (875 5575);
DOT 1 (425 5575);
DOT 1 (875 5175);
DOT 1 (425 5175);
DOT 1 (-50 7100);
DOT 1 (-500 7100);
DOT 1 (-950 7100);
DOT 1 (-1400 7100);
DOT 1 (-50 6700);
DOT 1 (-50 6325);
DOT 1 (-50 5925);
DOT 1 (-500 6700);
DOT 1 (-500 6325);
DOT 1 (-500 5925);
DOT 1 (-25 5575);
DOT 1 (-25 5175);
DOT 1 (-475 5575);
DOT 1 (-475 5175);
DOT 1 (-950 6700);
DOT 1 (-950 6325);
DOT 1 (-950 5925);
DOT 1 (-1400 6700);
DOT 1 (-1400 6325);
DOT 1 (-1400 5925);
DOT 1 (-925 5575);
DOT 1 (-925 5175);
DOT 1 (-1375 5575);
DOT 1 (-1375 5175);
DOT 1 (425 4800);
DOT 1 (-25 4800);
DOT 1 (-475 4800);
DOT 1 (-925 4800);
DOT 1 (-1375 4800);
DOT 1 (875 4400);
DOT 1 (425 4400);
DOT 1 (-25 4400);
DOT 1 (-475 4400);
DOT 1 (-625 2825);
DOT 1 (-925 4400);
DOT 1 (-1375 4400);
DOT 1 (-1075 3225);
DOT 1 (-1075 2825);
DOT 1 (-1525 3225);
DOT 1 (-1525 2825);
DOT 1 (-1850 7100);
DOT 1 (-2300 7100);
DOT 1 (-2750 7100);
DOT 1 (-3675 7100);
DOT 1 (-1850 6700);
DOT 1 (-1850 6325);
DOT 1 (-1850 5925);
DOT 1 (-2300 6700);
DOT 1 (-2300 6325);
DOT 1 (-2300 5925);
DOT 1 (-1825 5575);
DOT 1 (-1825 5175);
DOT 1 (-2275 5575);
DOT 1 (-2275 5175);
DOT 1 (-2750 6325);
DOT 1 (-3225 6700);
DOT 1 (-3675 6700);
DOT 1 (-3225 5925);
DOT 1 (-3675 6325);
DOT 1 (-3675 5925);
DOT 1 (-2725 5575);
DOT 1 (-3200 5175);
DOT 1 (-3650 5575);
DOT 1 (-3650 5175);
DOT 1 (-4125 7100);
DOT 1 (-4575 7100);
DOT 1 (-5025 7100);
DOT 1 (-5475 7100);
DOT 1 (-4125 6700);
DOT 1 (-4125 6325);
DOT 1 (-4125 5925);
DOT 1 (-4575 6700);
DOT 1 (-4575 6325);
DOT 1 (-4575 5925);
DOT 1 (-4100 5575);
DOT 1 (-4100 5175);
DOT 1 (-4550 5575);
DOT 1 (-4550 5175);
DOT 1 (-5025 6700);
DOT 1 (-5025 6325);
DOT 1 (-5025 5925);
DOT 1 (-5475 6700);
DOT 1 (-5475 6325);
DOT 1 (-5475 5925);
DOT 1 (-5000 5575);
DOT 1 (-5000 5175);
DOT 1 (-5450 5575);
DOT 1 (-5450 5175);
DOT 1 (-5000 4800);
DOT 1 (-1825 4800);
DOT 1 (-2275 4800);
DOT 1 (-2725 4800);
DOT 1 (-3650 4800);
DOT 1 (-4100 4800);
DOT 1 (-4550 4800);
DOT 1 (-5450 4800);
DOT 1 (-1825 4400);
DOT 1 (-2275 4400);
DOT 1 (-1975 3225);
DOT 1 (-3200 4400);
DOT 1 (-3650 4400);
DOT 1 (-3650 4025);
DOT 1 (-3200 3625);
DOT 1 (-3200 2825);
DOT 1 (-3650 3625);
DOT 1 (-3650 3225);
DOT 1 (-3650 2825);
DOT 1 (-2750 2000);
DOT 1 (-3200 2400);
DOT 1 (-3200 2000);
DOT 1 (-3650 2400);
DOT 1 (-3650 2000);
DOT 1 (-4100 4400);
DOT 1 (-4100 4025);
DOT 1 (-4550 4400);
DOT 1 (-4550 4025);
DOT 1 (-4100 3625);
DOT 1 (-4100 3225);
DOT 1 (-4100 2825);
DOT 1 (-4550 3625);
DOT 1 (-4550 3225);
DOT 1 (-4550 2825);
DOT 1 (-5000 4400);
DOT 1 (-5000 4025);
DOT 1 (-5450 4400);
DOT 1 (-5450 4025);
DOT 1 (-5000 3625);
DOT 1 (-5000 3225);
DOT 1 (-5450 3625);
DOT 1 (-4100 2400);
DOT 1 (-4100 2000);
DOT 1 (-4550 2400);
DOT 1 (-4550 2000);
DOT 1 (-5000 2400);
DOT 1 (-5000 2000);
DOT 1 (-5450 2400);
DOT 1 (-5450 2000);
DOT 1 (-5925 7100);
DOT 1 (-6375 7100);
DOT 1 (-6825 7100);
DOT 1 (-7275 7100);
DOT 1 (-5925 6700);
DOT 1 (-5925 6325);
DOT 1 (-5925 5925);
DOT 1 (-6375 6700);
DOT 1 (-6375 6325);
DOT 1 (-6375 5925);
DOT 1 (-5900 5575);
DOT 1 (-5900 5175);
DOT 1 (-6350 5575);
DOT 1 (-6350 5175);
DOT 1 (-6825 6700);
DOT 1 (-6825 6325);
DOT 1 (-6825 5925);
DOT 1 (-7275 6325);
DOT 1 (-6800 5575);
DOT 1 (-7250 5575);
DOT 1 (-6800 5175);
DOT 1 (-6350 4800);
DOT 1 (-5900 4800);
DOT 1 (-6800 4800);
DOT 1 (-7250 4800);
DOT 1 (-5900 4400);
DOT 1 (-5900 4025);
DOT 1 (-6350 4400);
DOT 1 (-6350 4025);
DOT 1 (-5900 3625);
DOT 1 (-5900 2825);
DOT 1 (-6350 3625);
DOT 1 (-6350 3225);
DOT 1 (-6350 2825);
DOT 1 (-6800 4400);
DOT 1 (-6800 4025);
DOT 1 (-7250 4025);
DOT 1 (-6800 3625);
DOT 1 (-6800 3225);
DOT 1 (-6800 2825);
DOT 1 (-7250 3225);
DOT 1 (-5900 2400);
DOT 1 (-6350 2400);
DOT 1 (-6350 2000);
DOT 1 (-6800 2400);
DOT 1 (-7250 2400);
DOT 1 (-6800 2000);
FORCENOTE
PVCCIN: 10 0805 100UF MLCC CAPS ON TOP
(-6800 4100) 0;
DISPLAY LEFT (-6800 4100);
DISPLAY 1.021277 (-6800 4100);
PAINT SKYBLUE (-6800 4100);
QUIT
